FILE_TYPE = MACRO_DRAWING;
SET COLOR_WIRE YELLOW;
SET COLOR_PROP ORANGE;
SET COLOR_DOT WHITE;
SET COLOR_ARC YELLOW;
SET COLOR_BODY GREEN;
SET COLOR_NOTE PURPLE;
SET PROP_DISPLAY VALUE;
SET PAGE_NUMBER P451;
FORCEADD OFFPAGE..1
R 2
(-2375 2675);
FORCEPROP 2 LAST $XR0 343 
J 0
(-2189 2675);
DISPLAY 0.638298 (-2189 2675);
PAINT MONO (-2189 2675);
FORCEPROP 2 LAST CDS_LIB standard
J 0
(-2375 2675);
DISPLAY INVISIBLE (-2375 2675);
FORCEPROP 1 LAST OFFPAGE TRUE
J 2
(-2700 2550);
DISPLAY 0.872340 (-2700 2550);
DISPLAY INVISIBLE (-2700 2550);
FORCEPROP 1 LAST COMMENT_BODY TRUE
J 2
(-2500 2575);
DISPLAY 0.872340 (-2500 2575);
PAINT GREEN (-2500 2575);
DISPLAY INVISIBLE (-2500 2575);
FORCEPROP 2 LAST PATH I100
J 0
(-2200 2750);
DISPLAY 0.680851 (-2200 2750);
DISPLAY INVISIBLE (-2200 2750);
FORCEADD Q_RES..1
(-2675 3225);
FORCEPROP 1 LAST LOCATION R1416
J 0
(-2800 3225);
DISPLAY 0.787234 (-2800 3225);
PAINT WHITE (-2800 3225);
FORCEPROP 0 LAST $SEC 1
J 0
(-2300 3275);
DISPLAY 0.680851 (-2300 3275);
PAINT MONO (-2300 3275);
DISPLAY INVISIBLE (-2300 3275);
FORCEPROP 0 LAST CDS_SEC 1
J 0
(-2300 3275);
DISPLAY 0.680851 (-2300 3275);
DISPLAY INVISIBLE (-2300 3275);
FORCEPROP 1 LASTPIN (-2775 3225) $PN 1
J 0
(-2763 3237);
DISPLAY 0.787234 (-2763 3237);
PAINT MONO (-2763 3237);
FORCEPROP 1 LASTPIN (-2575 3225) $PN 2
J 0
(-2613 3237);
DISPLAY 0.787234 (-2613 3237);
PAINT MONO (-2613 3237);
FORCEPROP 1 LAST VALUE 1K
J 2
(-2475 3225);
DISPLAY 0.638298 (-2475 3225);
FORCEPROP 1 LAST MATERIAL CHIP
J 0
(-2450 3225);
DISPLAY 0.638298 (-2450 3225);
FORCEPROP 1 LAST PACK_TYPE 0201LF
J 0
(-2300 3225);
DISPLAY 0.638298 (-2300 3225);
FORCEPROP 1 LAST TOLERANCE 1%
J 0
(-2675 3125);
DISPLAY 0.638298 (-2675 3125);
DISPLAY INVISIBLE (-2675 3125);
FORCEPROP 1 LAST WATTAGE 1/20W
J 2
(-2700 3075);
DISPLAY 0.638298 (-2700 3075);
DISPLAY INVISIBLE (-2700 3075);
FORCEPROP 2 LAST CDS_LIB pure_quanta
J 0
(-2675 3225);
DISPLAY INVISIBLE (-2675 3225);
FORCEPROP 1 LAST PATH I102
J 0
(-2725 3375);
DISPLAY 0.978723 (-2725 3375);
PAINT WHITE (-2725 3375);
DISPLAY INVISIBLE (-2725 3375);
FORCEPROP 1 LAST PART_NUMBER CS21001FE07
J 0
(-2725 3325);
DISPLAY 0.978723 (-2725 3325);
DISPLAY INVISIBLE (-2725 3325);
FORCEADD UNIVERSAL_GND..1
R 1
(-1925 2275);
FORCEPROP 3 LASTPIN (-1975 2275) SIG_NAME GND\g
J 0
(-1965 2285);
DISPLAY 0.659574 (-1965 2285);
PAINT MONO (-1965 2285);
DISPLAY INVISIBLE (-1965 2285);
FORCEPROP 2 LAST CDS_LIB pure_quanta_power
J 0
(-1925 2275);
DISPLAY INVISIBLE (-1925 2275);
FORCEPROP 1 LAST HDL_POWER GND
R 1
J 1
(-1850 2300);
DISPLAY 0.872340 (-1850 2300);
PAINT GREEN (-1850 2300);
DISPLAY INVISIBLE (-1850 2300);
FORCEPROP 1 LAST PATH I107
R 1
J 0
(-1925 2350);
DISPLAY 0.872340 (-1925 2350);
PAINT AQUA (-1925 2350);
DISPLAY INVISIBLE (-1925 2350);
FORCEADD GND..1
(-1500 2900);
FORCEPROP 3 LASTPIN (-1500 2950) SIG_NAME GND\g
J 0
(-1490 2960);
DISPLAY 0.659574 (-1490 2960);
PAINT MONO (-1490 2960);
DISPLAY INVISIBLE (-1490 2960);
FORCEPROP 2 LAST CDS_LIB pure_quanta_power
J 0
(-1500 2900);
DISPLAY INVISIBLE (-1500 2900);
FORCEPROP 1 LAST SIZE 1B
J 0
(-1425 2850);
DISPLAY 0.851064 (-1425 2850);
PAINT GREEN (-1425 2850);
DISPLAY INVISIBLE (-1425 2850);
FORCEPROP 2 LAST BOM_COST MEM
J 0
(-1600 2975);
DISPLAY 0.808511 (-1600 2975);
DISPLAY INVISIBLE (-1600 2975);
FORCEPROP 1 LAST HDL_POWER GND
J 0
(-1500 3050);
DISPLAY 0.851064 (-1500 3050);
PAINT GREEN (-1500 3050);
DISPLAY INVISIBLE (-1500 3050);
FORCEPROP 1 LAST PATH I108
J 0
(-1425 2900);
DISPLAY 0.872340 (-1425 2900);
PAINT AQUA (-1425 2900);
DISPLAY INVISIBLE (-1425 2900);
FORCEADD UNIVERSAL_GND..1
R 1
(-1925 3225);
FORCEPROP 3 LASTPIN (-1975 3225) SIG_NAME GND\g
J 0
(-1965 3235);
DISPLAY 0.659574 (-1965 3235);
PAINT MONO (-1965 3235);
DISPLAY INVISIBLE (-1965 3235);
FORCEPROP 2 LAST CDS_LIB pure_quanta_power
J 0
(-1925 3225);
DISPLAY INVISIBLE (-1925 3225);
FORCEPROP 1 LAST HDL_POWER GND
R 1
J 1
(-1850 3250);
DISPLAY 0.872340 (-1850 3250);
PAINT GREEN (-1850 3250);
DISPLAY INVISIBLE (-1850 3250);
FORCEPROP 1 LAST PATH I109
R 1
J 0
(-1925 3300);
DISPLAY 0.872340 (-1925 3300);
PAINT AQUA (-1925 3300);
DISPLAY INVISIBLE (-1925 3300);
FORCEADD Q_RES..2
(-1500 3300);
FORCEPROP 1 LAST LOCATION R1427
J 0
(-1455 3425);
DISPLAY 0.787234 (-1455 3425);
PAINT WHITE (-1455 3425);
FORCEPROP 0 LAST $SEC 1
J 0
(-1450 3475);
DISPLAY 0.680851 (-1450 3475);
PAINT MONO (-1450 3475);
DISPLAY INVISIBLE (-1450 3475);
FORCEPROP 0 LAST CDS_SEC 1
J 0
(-1450 3475);
DISPLAY 0.680851 (-1450 3475);
DISPLAY INVISIBLE (-1450 3475);
FORCEPROP 1 LASTPIN (-1500 3400) $PN 1
J 0
(-1495 3362);
DISPLAY 0.787234 (-1495 3362);
PAINT MONO (-1495 3362);
FORCEPROP 1 LASTPIN (-1500 3200) $PN 2
J 0
(-1495 3210);
DISPLAY 0.787234 (-1495 3210);
PAINT MONO (-1495 3210);
FORCEPROP 1 LAST MATERIAL CHIP
J 0
(-1460 3225);
DISPLAY 0.787234 (-1460 3225);
FORCEPROP 1 LAST TOLERANCE 1%
J 0
(-1455 3325);
DISPLAY 0.787234 (-1455 3325);
FORCEPROP 1 LAST VALUE 10K
J 0
(-1455 3375);
DISPLAY 0.787234 (-1455 3375);
FORCEPROP 1 LAST WATTAGE 1/20W
J 0
(-1460 3275);
DISPLAY 0.787234 (-1460 3275);
FORCEPROP 1 LAST PACK_TYPE 0201LF
J 0
(-1460 3125);
DISPLAY 0.787234 (-1460 3125);
FORCEPROP 2 LAST CDS_LIB pure_quanta
J 0
(-1500 3300);
DISPLAY INVISIBLE (-1500 3300);
FORCEPROP 1 LAST PATH I113
J 0
(-1450 3475);
DISPLAY 0.978723 (-1450 3475);
PAINT WHITE (-1450 3475);
DISPLAY INVISIBLE (-1450 3475);
FORCEPROP 1 LAST PART_NUMBER CS31001FE17
J 0
(-1460 3175);
DISPLAY 0.510638 (-1460 3175);
DISPLAY INVISIBLE (-1460 3175);
FORCEADD Q_RES..2
(-1500 3825);
FORCEPROP 1 LAST LOCATION R1426
J 0
(-1455 3950);
DISPLAY 0.787234 (-1455 3950);
PAINT WHITE (-1455 3950);
FORCEPROP 0 LAST $SEC 1
J 0
(-1450 4000);
DISPLAY 0.680851 (-1450 4000);
PAINT MONO (-1450 4000);
DISPLAY INVISIBLE (-1450 4000);
FORCEPROP 0 LAST CDS_SEC 1
J 0
(-1450 4000);
DISPLAY 0.680851 (-1450 4000);
DISPLAY INVISIBLE (-1450 4000);
FORCEPROP 1 LASTPIN (-1500 3925) $PN 1
J 0
(-1495 3887);
DISPLAY 0.787234 (-1495 3887);
PAINT MONO (-1495 3887);
FORCEPROP 1 LASTPIN (-1500 3725) $PN 2
J 0
(-1495 3735);
DISPLAY 0.787234 (-1495 3735);
PAINT MONO (-1495 3735);
FORCEPROP 1 LAST VALUE 1K
J 0
(-1455 3900);
DISPLAY 0.787234 (-1455 3900);
FORCEPROP 1 LAST MATERIAL EMPTY
J 0
(-1460 3750);
DISPLAY 0.787234 (-1460 3750);
PAINT RED (-1460 3750);
FORCEPROP 1 LAST PACK_TYPE 0201LF
J 0
(-1460 3650);
DISPLAY 0.787234 (-1460 3650);
FORCEPROP 1 LAST WATTAGE 1/20W
J 0
(-1460 3800);
DISPLAY 0.787234 (-1460 3800);
FORCEPROP 1 LAST TOLERANCE 1%
J 0
(-1455 3850);
DISPLAY 0.787234 (-1455 3850);
FORCEPROP 2 LAST CDS_LIB pure_quanta
J 0
(-1500 3825);
DISPLAY INVISIBLE (-1500 3825);
FORCEPROP 1 LAST PATH I114
J 0
(-1450 4000);
DISPLAY 0.978723 (-1450 4000);
PAINT WHITE (-1450 4000);
DISPLAY INVISIBLE (-1450 4000);
FORCEPROP 1 LAST PART_NUMBER CS21001FE07
J 0
(-1460 3700);
DISPLAY 0.978723 (-1460 3700);
DISPLAY INVISIBLE (-1460 3700);
FORCEADD P1V0..1
(-1500 4225);
FORCEPROP 3 LASTPIN (-1500 4175) SIG_NAME P1V8_CPU1_RT_1D\g
J 0
(-1490 4185);
DISPLAY 0.659574 (-1490 4185);
PAINT MONO (-1490 4185);
DISPLAY INVISIBLE (-1490 4185);
FORCEPROP 1 LAST HDL_POWER P1V8_CPU1_RT_1D
J 1
(-1500 4275);
DISPLAY 0.489362 (-1500 4275);
PAINT SKYBLUE (-1500 4275);
FORCEPROP 2 LAST CDS_LIB pure_quanta_power
J 0
(-1500 4225);
DISPLAY INVISIBLE (-1500 4225);
FORCEPROP 1 LAST PATH I115
J 0
(-1450 4250);
DISPLAY 0.872340 (-1450 4250);
PAINT AQUA (-1450 4250);
DISPLAY INVISIBLE (-1450 4250);
FORCEADD OFFPAGE..1
R 2
(-650 3550);
FORCEPROP 2 LAST $XR0 343 
J 0
(-464 3550);
DISPLAY 0.638298 (-464 3550);
PAINT MONO (-464 3550);
FORCEPROP 2 LAST CDS_LIB standard
J 0
(-650 3550);
DISPLAY INVISIBLE (-650 3550);
FORCEPROP 1 LAST OFFPAGE TRUE
J 2
(-975 3425);
DISPLAY 0.872340 (-975 3425);
DISPLAY INVISIBLE (-975 3425);
FORCEPROP 1 LAST COMMENT_BODY TRUE
J 2
(-775 3450);
DISPLAY 0.872340 (-775 3450);
PAINT GREEN (-775 3450);
DISPLAY INVISIBLE (-775 3450);
FORCEPROP 2 LAST PATH I116
J 0
(-475 3625);
DISPLAY 0.680851 (-475 3625);
DISPLAY INVISIBLE (-475 3625);
FORCEADD Q_RES..2
(-8950 3425);
FORCEPROP 1 LAST LOCATION R869
J 0
(-8905 3550);
DISPLAY 0.978723 (-8905 3550);
PAINT WHITE (-8905 3550);
FORCEPROP 0 LAST $SEC 1
J 0
(-8900 3600);
DISPLAY 0.680851 (-8900 3600);
PAINT MONO (-8900 3600);
DISPLAY INVISIBLE (-8900 3600);
FORCEPROP 0 LAST CDS_SEC 1
J 0
(-8900 3600);
DISPLAY 0.680851 (-8900 3600);
DISPLAY INVISIBLE (-8900 3600);
FORCEPROP 1 LASTPIN (-8950 3525) $PN 1
J 0
(-8945 3487);
DISPLAY 0.787234 (-8945 3487);
PAINT MONO (-8945 3487);
FORCEPROP 1 LASTPIN (-8950 3325) $PN 2
J 0
(-8945 3335);
DISPLAY 0.787234 (-8945 3335);
PAINT MONO (-8945 3335);
FORCEPROP 1 LAST MATERIAL CHIP
J 0
(-8910 3350);
DISPLAY 0.978723 (-8910 3350);
FORCEPROP 1 LAST WATTAGE 1/20W
J 0
(-8910 3400);
DISPLAY 0.978723 (-8910 3400);
FORCEPROP 1 LAST VALUE 200
J 0
(-8905 3500);
DISPLAY 0.978723 (-8905 3500);
FORCEPROP 1 LAST TOLERANCE 1%
J 0
(-8905 3450);
DISPLAY 0.978723 (-8905 3450);
FORCEPROP 1 LAST PACK_TYPE 0201LF
J 0
(-8910 3250);
DISPLAY 0.978723 (-8910 3250);
FORCEPROP 2 LAST CDS_LIB pure_quanta
J 0
(-8950 3425);
DISPLAY INVISIBLE (-8950 3425);
FORCEPROP 1 LAST PATH I119
J 0
(-8900 3600);
DISPLAY 0.978723 (-8900 3600);
PAINT WHITE (-8900 3600);
DISPLAY INVISIBLE (-8900 3600);
FORCEPROP 1 LAST PART_NUMBER CS12001FE12
J 0
(-8910 3300);
DISPLAY 0.978723 (-8910 3300);
DISPLAY INVISIBLE (-8910 3300);
FORCEADD OFFPAGE..5
(-2575 950);
FORCEPROP 2 LAST $XR0 343 
J 0
(-2860 950);
DISPLAY 0.638298 (-2860 950);
PAINT MONO (-2860 950);
FORCEPROP 2 LAST CDS_LIB standard
J 0
(-2575 950);
DISPLAY INVISIBLE (-2575 950);
FORCEPROP 1 LAST OFFPAGE TRUE
J 0
(-2250 825);
DISPLAY 0.872340 (-2250 825);
PAINT GREEN (-2250 825);
DISPLAY INVISIBLE (-2250 825);
FORCEPROP 1 LAST COMMENT_BODY TRUE
J 0
(-2475 875);
DISPLAY 0.872340 (-2475 875);
PAINT GREEN (-2475 875);
DISPLAY INVISIBLE (-2475 875);
FORCEPROP 2 LAST PATH I121
J 0
(-2525 1025);
DISPLAY 0.680851 (-2525 1025);
DISPLAY INVISIBLE (-2525 1025);
FORCEADD OFFPAGE..5
(-2575 1000);
FORCEPROP 2 LAST $XR0 343 
J 0
(-2860 1000);
DISPLAY 0.638298 (-2860 1000);
PAINT MONO (-2860 1000);
FORCEPROP 2 LAST CDS_LIB standard
J 0
(-2575 1000);
DISPLAY INVISIBLE (-2575 1000);
FORCEPROP 1 LAST OFFPAGE TRUE
J 0
(-2250 875);
DISPLAY 0.872340 (-2250 875);
PAINT GREEN (-2250 875);
DISPLAY INVISIBLE (-2250 875);
FORCEPROP 1 LAST COMMENT_BODY TRUE
J 0
(-2475 925);
DISPLAY 0.872340 (-2475 925);
PAINT GREEN (-2475 925);
DISPLAY INVISIBLE (-2475 925);
FORCEPROP 2 LAST PATH I122
J 0
(-2525 1075);
DISPLAY 0.680851 (-2525 1075);
DISPLAY INVISIBLE (-2525 1075);
FORCEADD OFFPAGE..5
(-2575 1050);
FORCEPROP 2 LAST $XR0 343 
J 0
(-2860 1050);
DISPLAY 0.638298 (-2860 1050);
PAINT MONO (-2860 1050);
FORCEPROP 2 LAST CDS_LIB standard
J 0
(-2575 1050);
DISPLAY INVISIBLE (-2575 1050);
FORCEPROP 1 LAST OFFPAGE TRUE
J 0
(-2250 925);
DISPLAY 0.872340 (-2250 925);
PAINT GREEN (-2250 925);
DISPLAY INVISIBLE (-2250 925);
FORCEPROP 1 LAST COMMENT_BODY TRUE
J 0
(-2475 975);
DISPLAY 0.872340 (-2475 975);
PAINT GREEN (-2475 975);
DISPLAY INVISIBLE (-2475 975);
FORCEPROP 2 LAST PATH I123
J 0
(-2525 1125);
DISPLAY 0.680851 (-2525 1125);
DISPLAY INVISIBLE (-2525 1125);
FORCEADD OFFPAGE..5
(-2575 1100);
FORCEPROP 2 LAST $XR0 343 
J 0
(-2860 1100);
DISPLAY 0.638298 (-2860 1100);
PAINT MONO (-2860 1100);
FORCEPROP 2 LAST CDS_LIB standard
J 2
(-2575 1100);
DISPLAY INVISIBLE (-2575 1100);
FORCEPROP 1 LAST OFFPAGE TRUE
J 0
(-2250 975);
DISPLAY 0.872340 (-2250 975);
PAINT GREEN (-2250 975);
DISPLAY INVISIBLE (-2250 975);
FORCEPROP 1 LAST COMMENT_BODY TRUE
J 0
(-2475 1025);
DISPLAY 0.872340 (-2475 1025);
PAINT GREEN (-2475 1025);
DISPLAY INVISIBLE (-2475 1025);
FORCEPROP 2 LAST PATH I124
J 0
(-2525 1175);
DISPLAY 0.680851 (-2525 1175);
DISPLAY INVISIBLE (-2525 1175);
FORCEADD Q_RES..2
(-1425 1350);
FORCEPROP 1 LAST LOCATION R1488
J 0
(-1380 1475);
DISPLAY 0.978723 (-1380 1475);
FORCEPROP 0 LAST $SEC 1
J 0
(-1375 1525);
DISPLAY 0.680851 (-1375 1525);
PAINT MONO (-1375 1525);
DISPLAY INVISIBLE (-1375 1525);
FORCEPROP 0 LAST CDS_SEC 1
J 0
(-1375 1525);
DISPLAY 0.680851 (-1375 1525);
DISPLAY INVISIBLE (-1375 1525);
FORCEPROP 1 LASTPIN (-1425 1450) $PN 1
J 0
(-1420 1412);
DISPLAY 0.787234 (-1420 1412);
PAINT MONO (-1420 1412);
FORCEPROP 1 LASTPIN (-1425 1250) $PN 2
J 0
(-1420 1260);
DISPLAY 0.787234 (-1420 1260);
PAINT MONO (-1420 1260);
FORCEPROP 1 LAST WATTAGE 1/20W
J 0
(-1385 1325);
DISPLAY 0.787234 (-1385 1325);
FORCEPROP 1 LAST VALUE 4.7K
J 0
(-1380 1425);
DISPLAY 0.787234 (-1380 1425);
FORCEPROP 1 LAST PACK_TYPE 0201LF
J 0
(-1375 1200);
DISPLAY 0.787234 (-1375 1200);
FORCEPROP 1 LAST TOLERANCE 5%
J 0
(-1380 1375);
DISPLAY 0.787234 (-1380 1375);
FORCEPROP 1 LAST MATERIAL EMPTY
J 0
(-1385 1275);
DISPLAY 0.787234 (-1385 1275);
PAINT RED (-1385 1275);
FORCEPROP 2 LAST CDS_LIB pure_quanta
J 0
(-1425 1350);
DISPLAY INVISIBLE (-1425 1350);
FORCEPROP 1 LAST PATH I132
J 0
(-1375 1525);
DISPLAY 0.978723 (-1375 1525);
PAINT WHITE (-1375 1525);
DISPLAY INVISIBLE (-1375 1525);
FORCEPROP 1 LAST PART_NUMBER CS24701JE04
J 0
(-1385 1225);
DISPLAY 0.978723 (-1385 1225);
DISPLAY INVISIBLE (-1385 1225);
FORCEADD GND..1
(-600 425);
FORCEPROP 3 LASTPIN (-600 475) SIG_NAME GND\g
J 0
(-590 485);
DISPLAY 0.659574 (-590 485);
PAINT MONO (-590 485);
DISPLAY INVISIBLE (-590 485);
FORCEPROP 1 LAST SIZE 1B
J 0
(-525 375);
DISPLAY 0.851064 (-525 375);
PAINT GREEN (-525 375);
DISPLAY INVISIBLE (-525 375);
FORCEPROP 2 LAST BOM_COST MEM
J 0
(-700 500);
DISPLAY 0.808511 (-700 500);
DISPLAY INVISIBLE (-700 500);
FORCEPROP 2 LAST CDS_LIB pure_quanta_power
J 0
(-600 425);
DISPLAY INVISIBLE (-600 425);
FORCEPROP 1 LAST HDL_POWER GND
J 0
(-600 575);
DISPLAY 0.851064 (-600 575);
PAINT GREEN (-600 575);
DISPLAY INVISIBLE (-600 575);
FORCEPROP 1 LAST PATH I134
J 0
(-525 425);
DISPLAY 0.872340 (-525 425);
PAINT AQUA (-525 425);
DISPLAY INVISIBLE (-525 425);
FORCEADD Q_RES..2
(-600 725);
FORCEPROP 1 LAST LOCATION R1417
J 0
(-555 850);
DISPLAY 0.787234 (-555 850);
FORCEPROP 0 LAST $SEC 1
J 0
(-550 900);
DISPLAY 0.680851 (-550 900);
PAINT MONO (-550 900);
DISPLAY INVISIBLE (-550 900);
FORCEPROP 0 LAST CDS_SEC 1
J 0
(-550 900);
DISPLAY 0.680851 (-550 900);
DISPLAY INVISIBLE (-550 900);
FORCEPROP 1 LASTPIN (-600 825) $PN 1
J 0
(-595 787);
DISPLAY 0.787234 (-595 787);
PAINT MONO (-595 787);
FORCEPROP 1 LASTPIN (-600 625) $PN 2
J 0
(-595 635);
DISPLAY 0.787234 (-595 635);
PAINT MONO (-595 635);
FORCEPROP 1 LAST MATERIAL CHIP
J 0
(-560 650);
DISPLAY 0.787234 (-560 650);
FORCEPROP 1 LAST PACK_TYPE 0201LF
J 0
(-560 550);
DISPLAY 0.787234 (-560 550);
FORCEPROP 1 LAST WATTAGE 1/20W
J 0
(-560 700);
DISPLAY 0.787234 (-560 700);
FORCEPROP 1 LAST TOLERANCE 5%
J 0
(-555 750);
DISPLAY 0.787234 (-555 750);
FORCEPROP 1 LAST VALUE 4.7K
J 0
(-555 800);
DISPLAY 0.787234 (-555 800);
FORCEPROP 2 LAST CDS_LIB pure_quanta
J 0
(-600 725);
DISPLAY INVISIBLE (-600 725);
FORCEPROP 1 LAST PATH I136
J 0
(-550 900);
DISPLAY 0.978723 (-550 900);
PAINT WHITE (-550 900);
DISPLAY INVISIBLE (-550 900);
FORCEPROP 1 LAST PART_NUMBER CS24701JE04
J 0
(-560 600);
DISPLAY 0.978723 (-560 600);
DISPLAY INVISIBLE (-560 600);
FORCEADD Q_RES..2
(-600 1375);
FORCEPROP 1 LAST LOCATION R1499
J 0
(-555 1500);
DISPLAY 0.787234 (-555 1500);
FORCEPROP 0 LAST $SEC 1
J 0
(-550 1550);
DISPLAY 0.680851 (-550 1550);
PAINT MONO (-550 1550);
DISPLAY INVISIBLE (-550 1550);
FORCEPROP 0 LAST CDS_SEC 1
J 0
(-550 1550);
DISPLAY 0.680851 (-550 1550);
DISPLAY INVISIBLE (-550 1550);
FORCEPROP 1 LASTPIN (-600 1475) $PN 1
J 0
(-595 1437);
DISPLAY 0.787234 (-595 1437);
PAINT MONO (-595 1437);
FORCEPROP 1 LASTPIN (-600 1275) $PN 2
J 0
(-595 1285);
DISPLAY 0.787234 (-595 1285);
PAINT MONO (-595 1285);
FORCEPROP 1 LAST MATERIAL EMPTY
J 0
(-560 1300);
DISPLAY 0.787234 (-560 1300);
PAINT RED (-560 1300);
FORCEPROP 1 LAST PACK_TYPE 0201LF
J 0
(-550 1225);
DISPLAY 0.787234 (-550 1225);
FORCEPROP 1 LAST WATTAGE 1/20W
J 0
(-560 1350);
DISPLAY 0.787234 (-560 1350);
FORCEPROP 1 LAST TOLERANCE 5%
J 0
(-555 1400);
DISPLAY 0.787234 (-555 1400);
FORCEPROP 1 LAST VALUE 4.7K
J 0
(-555 1450);
DISPLAY 0.787234 (-555 1450);
FORCEPROP 2 LAST CDS_LIB pure_quanta
J 2
(-600 1375);
DISPLAY INVISIBLE (-600 1375);
FORCEPROP 1 LAST PATH I137
J 0
(-550 1550);
DISPLAY 0.978723 (-550 1550);
PAINT WHITE (-550 1550);
DISPLAY INVISIBLE (-550 1550);
FORCEPROP 1 LAST PART_NUMBER CS24701JE04
J 0
(-560 1250);
DISPLAY 0.978723 (-560 1250);
DISPLAY INVISIBLE (-560 1250);
FORCEADD P1V0..1
(-600 1675);
FORCEPROP 3 LASTPIN (-600 1625) SIG_NAME P1V8_CPU1_RT_1D\g
J 0
(-590 1635);
DISPLAY 0.659574 (-590 1635);
PAINT MONO (-590 1635);
DISPLAY INVISIBLE (-590 1635);
FORCEPROP 1 LAST HDL_POWER P1V8_CPU1_RT_1D
J 1
(-600 1725);
DISPLAY 0.489362 (-600 1725);
PAINT SKYBLUE (-600 1725);
FORCEPROP 2 LAST CDS_LIB pure_quanta_power
J 0
(-600 1675);
DISPLAY INVISIBLE (-600 1675);
FORCEPROP 1 LAST PATH I138
J 0
(-550 1700);
DISPLAY 0.872340 (-550 1700);
PAINT AQUA (-550 1700);
DISPLAY INVISIBLE (-550 1700);
FORCEADD Q_RES..2
(-875 1350);
FORCEPROP 1 LAST LOCATION R1490
J 0
(-830 1475);
DISPLAY 0.978723 (-830 1475);
FORCEPROP 0 LAST $SEC 1
J 0
(-825 1525);
DISPLAY 0.680851 (-825 1525);
PAINT MONO (-825 1525);
DISPLAY INVISIBLE (-825 1525);
FORCEPROP 0 LAST CDS_SEC 1
J 0
(-825 1525);
DISPLAY 0.680851 (-825 1525);
DISPLAY INVISIBLE (-825 1525);
FORCEPROP 1 LASTPIN (-875 1450) $PN 1
J 0
(-870 1412);
DISPLAY 0.787234 (-870 1412);
PAINT MONO (-870 1412);
FORCEPROP 1 LASTPIN (-875 1250) $PN 2
J 0
(-870 1260);
DISPLAY 0.787234 (-870 1260);
PAINT MONO (-870 1260);
FORCEPROP 1 LAST MATERIAL EMPTY
J 0
(-835 1275);
DISPLAY 0.787234 (-835 1275);
PAINT RED (-835 1275);
FORCEPROP 1 LAST PACK_TYPE 0201LF
J 0
(-835 1175);
DISPLAY 0.787234 (-835 1175);
FORCEPROP 1 LAST VALUE 1K
J 0
(-830 1425);
DISPLAY 0.787234 (-830 1425);
FORCEPROP 1 LAST TOLERANCE 1%
J 0
(-830 1375);
DISPLAY 0.787234 (-830 1375);
FORCEPROP 1 LAST WATTAGE 1/20W
J 0
(-835 1325);
DISPLAY 0.787234 (-835 1325);
FORCEPROP 2 LAST CDS_LIB pure_quanta
J 0
(-875 1350);
DISPLAY INVISIBLE (-875 1350);
FORCEPROP 1 LAST PATH I139
J 0
(-825 1525);
DISPLAY 0.978723 (-825 1525);
PAINT WHITE (-825 1525);
DISPLAY INVISIBLE (-825 1525);
FORCEPROP 1 LAST PART_NUMBER CS21001FE07
J 0
(-835 1225);
DISPLAY 0.978723 (-835 1225);
DISPLAY INVISIBLE (-835 1225);
FORCEADD Q_RES..2
(-1150 1350);
FORCEPROP 1 LAST LOCATION R1489
J 0
(-1105 1475);
DISPLAY 0.978723 (-1105 1475);
FORCEPROP 0 LAST $SEC 1
J 0
(-1100 1525);
DISPLAY 0.680851 (-1100 1525);
PAINT MONO (-1100 1525);
DISPLAY INVISIBLE (-1100 1525);
FORCEPROP 0 LAST CDS_SEC 1
J 0
(-1100 1525);
DISPLAY 0.680851 (-1100 1525);
DISPLAY INVISIBLE (-1100 1525);
FORCEPROP 1 LASTPIN (-1150 1450) $PN 1
J 0
(-1145 1412);
DISPLAY 0.787234 (-1145 1412);
PAINT MONO (-1145 1412);
FORCEPROP 1 LASTPIN (-1150 1250) $PN 2
J 0
(-1145 1260);
DISPLAY 0.787234 (-1145 1260);
PAINT MONO (-1145 1260);
FORCEPROP 1 LAST MATERIAL EMPTY
J 0
(-1110 1275);
DISPLAY 0.787234 (-1110 1275);
PAINT RED (-1110 1275);
FORCEPROP 1 LAST PACK_TYPE 0201LF
J 0
(-1100 1200);
DISPLAY 0.787234 (-1100 1200);
FORCEPROP 1 LAST TOLERANCE 5%
J 0
(-1105 1375);
DISPLAY 0.787234 (-1105 1375);
FORCEPROP 1 LAST WATTAGE 1/20W
J 0
(-1110 1325);
DISPLAY 0.787234 (-1110 1325);
FORCEPROP 1 LAST VALUE 4.7K
J 0
(-1105 1425);
DISPLAY 0.787234 (-1105 1425);
FORCEPROP 2 LAST CDS_LIB pure_quanta
J 0
(-1150 1350);
DISPLAY INVISIBLE (-1150 1350);
FORCEPROP 1 LAST PATH I140
J 0
(-1100 1525);
DISPLAY 0.978723 (-1100 1525);
PAINT WHITE (-1100 1525);
DISPLAY INVISIBLE (-1100 1525);
FORCEPROP 1 LAST PART_NUMBER CS24701JE04
J 0
(-1110 1225);
DISPLAY 0.978723 (-1110 1225);
DISPLAY INVISIBLE (-1110 1225);
FORCEADD OFFPAGE..1
R 2
(-2700 3625);
FORCEPROP 2 LAST $XR0 343 
J 0
(-2514 3625);
DISPLAY 0.638298 (-2514 3625);
PAINT MONO (-2514 3625);
FORCEPROP 2 LAST CDS_LIB standard
J 0
(-2700 3625);
DISPLAY INVISIBLE (-2700 3625);
FORCEPROP 1 LAST OFFPAGE TRUE
J 2
(-3025 3500);
DISPLAY 0.872340 (-3025 3500);
DISPLAY INVISIBLE (-3025 3500);
FORCEPROP 1 LAST COMMENT_BODY TRUE
J 2
(-2825 3525);
DISPLAY 0.872340 (-2825 3525);
PAINT GREEN (-2825 3525);
DISPLAY INVISIBLE (-2825 3525);
FORCEPROP 2 LAST PATH I142
J 0
(-2525 3700);
DISPLAY 0.680851 (-2525 3700);
DISPLAY INVISIBLE (-2525 3700);
FORCEADD OFFPAGE..1
R 2
(-2700 3525);
FORCEPROP 2 LAST $XR0 343 
J 0
(-2514 3525);
DISPLAY 0.638298 (-2514 3525);
PAINT MONO (-2514 3525);
FORCEPROP 2 LAST CDS_LIB standard
J 0
(-2700 3525);
DISPLAY INVISIBLE (-2700 3525);
FORCEPROP 1 LAST OFFPAGE TRUE
J 2
(-3025 3400);
DISPLAY 0.872340 (-3025 3400);
DISPLAY INVISIBLE (-3025 3400);
FORCEPROP 1 LAST COMMENT_BODY TRUE
J 2
(-2825 3425);
DISPLAY 0.872340 (-2825 3425);
PAINT GREEN (-2825 3425);
DISPLAY INVISIBLE (-2825 3425);
FORCEPROP 2 LAST PATH I143
J 0
(-2525 3600);
DISPLAY 0.680851 (-2525 3600);
DISPLAY INVISIBLE (-2525 3600);
FORCEADD OFFPAGE..1
R 2
(-2700 3425);
FORCEPROP 2 LAST $XR0 343 
J 0
(-2514 3425);
DISPLAY 0.638298 (-2514 3425);
PAINT MONO (-2514 3425);
FORCEPROP 2 LAST CDS_LIB standard
J 0
(-2700 3425);
DISPLAY INVISIBLE (-2700 3425);
FORCEPROP 1 LAST OFFPAGE TRUE
J 2
(-3025 3300);
DISPLAY 0.872340 (-3025 3300);
DISPLAY INVISIBLE (-3025 3300);
FORCEPROP 1 LAST COMMENT_BODY TRUE
J 2
(-2825 3325);
DISPLAY 0.872340 (-2825 3325);
PAINT GREEN (-2825 3325);
DISPLAY INVISIBLE (-2825 3325);
FORCEPROP 2 LAST PATH I144
J 0
(-2525 3500);
DISPLAY 0.680851 (-2525 3500);
DISPLAY INVISIBLE (-2525 3500);
FORCEADD OFFPAGE..1
R 2
(-2725 3325);
FORCEPROP 2 LAST $XR0 343 
J 0
(-2539 3325);
DISPLAY 0.638298 (-2539 3325);
PAINT MONO (-2539 3325);
FORCEPROP 2 LAST CDS_LIB standard
J 0
(-2725 3325);
DISPLAY INVISIBLE (-2725 3325);
FORCEPROP 1 LAST OFFPAGE TRUE
J 2
(-3050 3200);
DISPLAY 0.872340 (-3050 3200);
DISPLAY INVISIBLE (-3050 3200);
FORCEPROP 1 LAST COMMENT_BODY TRUE
J 2
(-2850 3225);
DISPLAY 0.872340 (-2850 3225);
PAINT GREEN (-2850 3225);
DISPLAY INVISIBLE (-2850 3225);
FORCEPROP 2 LAST PATH I145
J 0
(-2550 3400);
DISPLAY 0.680851 (-2550 3400);
DISPLAY INVISIBLE (-2550 3400);
FORCEADD UNIVERSAL_GND..1
(-8950 3150);
FORCEPROP 3 LASTPIN (-8950 3200) SIG_NAME GND\g
J 0
(-8940 3210);
DISPLAY 0.659574 (-8940 3210);
PAINT MONO (-8940 3210);
DISPLAY INVISIBLE (-8940 3210);
FORCEPROP 2 LAST CDS_LIB pure_quanta_power
J 0
(-8950 3150);
DISPLAY INVISIBLE (-8950 3150);
FORCEPROP 1 LAST HDL_POWER GND
J 1
(-8925 3075);
DISPLAY 0.872340 (-8925 3075);
PAINT GREEN (-8925 3075);
DISPLAY INVISIBLE (-8925 3075);
FORCEPROP 1 LAST PATH I15
J 0
(-8875 3150);
DISPLAY 0.872340 (-8875 3150);
PAINT AQUA (-8875 3150);
DISPLAY INVISIBLE (-8875 3150);
FORCEADD Q_RES..2
(-8950 4100);
FORCEPROP 1 LAST LOCATION R868
J 0
(-8905 4225);
DISPLAY 0.787234 (-8905 4225);
FORCEPROP 0 LAST $SEC 1
J 0
(-8900 4275);
DISPLAY 0.680851 (-8900 4275);
PAINT MONO (-8900 4275);
DISPLAY INVISIBLE (-8900 4275);
FORCEPROP 0 LAST CDS_SEC 1
J 0
(-8900 4275);
DISPLAY 0.680851 (-8900 4275);
DISPLAY INVISIBLE (-8900 4275);
FORCEPROP 1 LASTPIN (-8950 4200) $PN 1
J 0
(-8945 4162);
DISPLAY 0.787234 (-8945 4162);
PAINT MONO (-8945 4162);
FORCEPROP 1 LASTPIN (-8950 4000) $PN 2
J 0
(-8945 4010);
DISPLAY 0.787234 (-8945 4010);
PAINT MONO (-8945 4010);
FORCEPROP 1 LAST PACK_TYPE 0201LF
J 0
(-8900 3950);
DISPLAY 0.787234 (-8900 3950);
FORCEPROP 1 LAST TOLERANCE 5%
J 0
(-8905 4125);
DISPLAY 0.787234 (-8905 4125);
FORCEPROP 1 LAST VALUE 4.7K
J 0
(-8905 4175);
DISPLAY 0.787234 (-8905 4175);
FORCEPROP 1 LAST WATTAGE 1/20W
J 0
(-8910 4075);
DISPLAY 0.787234 (-8910 4075);
FORCEPROP 1 LAST MATERIAL EMPTY
J 0
(-8910 4025);
DISPLAY 0.787234 (-8910 4025);
FORCEPROP 2 LAST CDS_LIB pure_quanta
J 0
(-8950 4100);
DISPLAY INVISIBLE (-8950 4100);
FORCEPROP 1 LAST PATH I17
J 0
(-8900 4275);
DISPLAY 0.978723 (-8900 4275);
PAINT WHITE (-8900 4275);
DISPLAY INVISIBLE (-8900 4275);
FORCEPROP 1 LAST PART_NUMBER CS24701JE04
J 0
(-8910 3975);
DISPLAY 0.978723 (-8910 3975);
DISPLAY INVISIBLE (-8910 3975);
FORCEADD P1V0..1
(-8950 4425);
FORCEPROP 3 LASTPIN (-8950 4375) SIG_NAME P1V8_CPU1_RT_1D\g
J 0
(-8940 4385);
DISPLAY 0.659574 (-8940 4385);
PAINT MONO (-8940 4385);
DISPLAY INVISIBLE (-8940 4385);
FORCEPROP 1 LAST HDL_POWER P1V8_CPU1_RT_1D
J 1
(-8950 4475);
DISPLAY 0.489362 (-8950 4475);
PAINT SKYBLUE (-8950 4475);
FORCEPROP 2 LAST CDS_LIB pure_quanta_power
J 0
(-8950 4425);
DISPLAY INVISIBLE (-8950 4425);
FORCEPROP 1 LAST PATH I18
J 0
(-8900 4450);
DISPLAY 0.872340 (-8900 4450);
PAINT AQUA (-8900 4450);
DISPLAY INVISIBLE (-8900 4450);
FORCEADD Q_RES..2
(-8925 5025);
FORCEPROP 1 LAST LOCATION R875
J 0
(-8880 5150);
DISPLAY 0.787234 (-8880 5150);
FORCEPROP 0 LAST $SEC 1
J 0
(-8875 5200);
DISPLAY 0.680851 (-8875 5200);
PAINT MONO (-8875 5200);
DISPLAY INVISIBLE (-8875 5200);
FORCEPROP 0 LAST CDS_SEC 1
J 0
(-8875 5200);
DISPLAY 0.680851 (-8875 5200);
DISPLAY INVISIBLE (-8875 5200);
FORCEPROP 1 LASTPIN (-8925 5125) $PN 1
J 0
(-8920 5087);
DISPLAY 0.787234 (-8920 5087);
PAINT MONO (-8920 5087);
FORCEPROP 1 LASTPIN (-8925 4925) $PN 2
J 0
(-8920 4935);
DISPLAY 0.787234 (-8920 4935);
PAINT MONO (-8920 4935);
FORCEPROP 1 LAST PACK_TYPE 0201LF
J 0
(-8885 4850);
DISPLAY 0.787234 (-8885 4850);
FORCEPROP 1 LAST MATERIAL CHIP
J 0
(-8885 4950);
DISPLAY 0.787234 (-8885 4950);
FORCEPROP 1 LAST WATTAGE 1/20W
J 0
(-8885 5000);
DISPLAY 0.787234 (-8885 5000);
FORCEPROP 1 LAST TOLERANCE 1%
J 0
(-8880 5050);
DISPLAY 0.787234 (-8880 5050);
FORCEPROP 1 LAST VALUE 10K
J 0
(-8880 5100);
DISPLAY 0.787234 (-8880 5100);
FORCEPROP 2 LAST CDS_LIB pure_quanta
J 0
(-8925 5025);
DISPLAY INVISIBLE (-8925 5025);
FORCEPROP 1 LAST PATH I19
J 0
(-8875 5200);
DISPLAY 0.978723 (-8875 5200);
PAINT WHITE (-8875 5200);
DISPLAY INVISIBLE (-8875 5200);
FORCEPROP 1 LAST PART_NUMBER CS31001FE17
J 0
(-8885 4900);
DISPLAY 0.638298 (-8885 4900);
DISPLAY INVISIBLE (-8885 4900);
FORCEADD Q_RES..2
(-8625 5025);
FORCEPROP 1 LAST LOCATION R876
J 0
(-8580 5150);
DISPLAY 0.787234 (-8580 5150);
FORCEPROP 0 LAST $SEC 1
J 0
(-8575 5200);
DISPLAY 0.680851 (-8575 5200);
PAINT MONO (-8575 5200);
DISPLAY INVISIBLE (-8575 5200);
FORCEPROP 0 LAST CDS_SEC 1
J 0
(-8575 5200);
DISPLAY 0.680851 (-8575 5200);
DISPLAY INVISIBLE (-8575 5200);
FORCEPROP 1 LASTPIN (-8625 5125) $PN 1
J 0
(-8620 5087);
DISPLAY 0.787234 (-8620 5087);
PAINT MONO (-8620 5087);
FORCEPROP 1 LASTPIN (-8625 4925) $PN 2
J 0
(-8620 4935);
DISPLAY 0.787234 (-8620 4935);
PAINT MONO (-8620 4935);
FORCEPROP 1 LAST PACK_TYPE 0201LF
J 0
(-8585 4850);
DISPLAY 0.787234 (-8585 4850);
FORCEPROP 1 LAST MATERIAL CHIP
J 0
(-8585 4950);
DISPLAY 0.787234 (-8585 4950);
FORCEPROP 1 LAST WATTAGE 1/20W
J 0
(-8585 5000);
DISPLAY 0.787234 (-8585 5000);
FORCEPROP 1 LAST TOLERANCE 1%
J 0
(-8580 5050);
DISPLAY 0.787234 (-8580 5050);
FORCEPROP 1 LAST VALUE 10K
J 0
(-8580 5100);
DISPLAY 0.787234 (-8580 5100);
FORCEPROP 2 LAST CDS_LIB pure_quanta
J 0
(-8625 5025);
DISPLAY INVISIBLE (-8625 5025);
FORCEPROP 1 LAST PATH I20
J 0
(-8575 5200);
DISPLAY 0.978723 (-8575 5200);
PAINT WHITE (-8575 5200);
DISPLAY INVISIBLE (-8575 5200);
FORCEPROP 1 LAST PART_NUMBER CS31001FE17
J 0
(-8585 4900);
DISPLAY 0.510638 (-8585 4900);
DISPLAY INVISIBLE (-8585 4900);
FORCEADD Q_RES..2
(-8925 5975);
FORCEPROP 1 LAST LOCATION R874
J 0
(-8880 6100);
DISPLAY 0.787234 (-8880 6100);
FORCEPROP 0 LAST $SEC 1
J 0
(-8875 6150);
DISPLAY 0.680851 (-8875 6150);
PAINT MONO (-8875 6150);
DISPLAY INVISIBLE (-8875 6150);
FORCEPROP 0 LAST CDS_SEC 1
J 0
(-8875 6150);
DISPLAY 0.680851 (-8875 6150);
DISPLAY INVISIBLE (-8875 6150);
FORCEPROP 1 LASTPIN (-8925 6075) $PN 1
J 0
(-8920 6037);
DISPLAY 0.787234 (-8920 6037);
PAINT MONO (-8920 6037);
FORCEPROP 1 LASTPIN (-8925 5875) $PN 2
J 0
(-8920 5885);
DISPLAY 0.787234 (-8920 5885);
PAINT MONO (-8920 5885);
FORCEPROP 1 LAST WATTAGE 1/20W
J 0
(-8885 5950);
DISPLAY 0.787234 (-8885 5950);
FORCEPROP 1 LAST VALUE 4.7K
J 0
(-8880 6050);
DISPLAY 0.787234 (-8880 6050);
FORCEPROP 1 LAST MATERIAL EMPTY
J 0
(-8885 5900);
DISPLAY 0.787234 (-8885 5900);
FORCEPROP 1 LAST PACK_TYPE 0201LF
J 0
(-8875 5825);
DISPLAY 0.787234 (-8875 5825);
FORCEPROP 1 LAST TOLERANCE 5%
J 0
(-8880 6000);
DISPLAY 0.787234 (-8880 6000);
FORCEPROP 2 LAST CDS_LIB pure_quanta
J 0
(-8925 5975);
DISPLAY INVISIBLE (-8925 5975);
FORCEPROP 1 LAST PATH I21
J 0
(-8875 6150);
DISPLAY 0.978723 (-8875 6150);
PAINT WHITE (-8875 6150);
DISPLAY INVISIBLE (-8875 6150);
FORCEPROP 1 LAST PART_NUMBER CS24701JE04
J 0
(-8885 5850);
DISPLAY 0.978723 (-8885 5850);
DISPLAY INVISIBLE (-8885 5850);
FORCEADD P1V0..1
(-8925 6375);
FORCEPROP 3 LASTPIN (-8925 6325) SIG_NAME P1V8_CPU1_RT_1D\g
J 0
(-8915 6335);
DISPLAY 0.659574 (-8915 6335);
PAINT MONO (-8915 6335);
DISPLAY INVISIBLE (-8915 6335);
FORCEPROP 1 LAST HDL_POWER P1V8_CPU1_RT_1D
J 1
(-8925 6425);
DISPLAY 0.489362 (-8925 6425);
PAINT SKYBLUE (-8925 6425);
FORCEPROP 2 LAST CDS_LIB pure_quanta_power
J 0
(-8925 6375);
DISPLAY INVISIBLE (-8925 6375);
FORCEPROP 1 LAST PATH I22
J 0
(-8875 6400);
DISPLAY 0.872340 (-8875 6400);
PAINT AQUA (-8875 6400);
DISPLAY INVISIBLE (-8875 6400);
FORCEADD OFFPAGE..1
(-8025 1025);
FORCEPROP 2 LAST $XR0 183 
J 0
(-8307 1025);
DISPLAY 0.638298 (-8307 1025);
PAINT MONO (-8307 1025);
FORCEPROP 2 LAST CDS_LIB standard
J 0
(-8025 1025);
DISPLAY INVISIBLE (-8025 1025);
FORCEPROP 1 LAST OFFPAGE TRUE
J 0
(-7700 900);
DISPLAY 0.872340 (-7700 900);
DISPLAY INVISIBLE (-7700 900);
FORCEPROP 1 LAST COMMENT_BODY TRUE
J 0
(-7900 925);
DISPLAY 0.872340 (-7900 925);
PAINT GREEN (-7900 925);
DISPLAY INVISIBLE (-7900 925);
FORCEPROP 2 LAST PATH I23
J 0
(-8275 1075);
DISPLAY 0.680851 (-8275 1075);
DISPLAY INVISIBLE (-8275 1075);
FORCEADD OFFPAGE..1
(-8025 1175);
FORCEPROP 2 LAST $XR0 183 
J 0
(-8307 1175);
DISPLAY 0.638298 (-8307 1175);
PAINT MONO (-8307 1175);
FORCEPROP 2 LAST CDS_LIB standard
J 0
(-8025 1175);
DISPLAY INVISIBLE (-8025 1175);
FORCEPROP 1 LAST OFFPAGE TRUE
J 0
(-7700 1050);
DISPLAY 0.872340 (-7700 1050);
DISPLAY INVISIBLE (-7700 1050);
FORCEPROP 1 LAST COMMENT_BODY TRUE
J 0
(-7900 1075);
DISPLAY 0.872340 (-7900 1075);
PAINT GREEN (-7900 1075);
DISPLAY INVISIBLE (-7900 1075);
FORCEPROP 2 LAST PATH I24
J 0
(-8275 1225);
DISPLAY 0.680851 (-8275 1225);
DISPLAY INVISIBLE (-8275 1225);
FORCEADD OFFPAGE..5
(-7750 1625);
FORCEPROP 2 LAST $XR1 186 
J 0
(-8155 1625);
DISPLAY 0.638298 (-8155 1625);
PAINT MONO (-8155 1625);
FORCEPROP 2 LAST $XR0 185 
J 0
(-8035 1625);
DISPLAY 0.638298 (-8035 1625);
PAINT MONO (-8035 1625);
FORCEPROP 2 LAST CDS_LIB standard
J 0
(-7750 1625);
DISPLAY INVISIBLE (-7750 1625);
FORCEPROP 1 LAST OFFPAGE TRUE
J 0
(-7425 1500);
DISPLAY 0.872340 (-7425 1500);
PAINT GREEN (-7425 1500);
DISPLAY INVISIBLE (-7425 1500);
FORCEPROP 1 LAST COMMENT_BODY TRUE
J 0
(-7650 1550);
DISPLAY 0.872340 (-7650 1550);
PAINT GREEN (-7650 1550);
DISPLAY INVISIBLE (-7650 1550);
FORCEPROP 2 LAST PATH I25
J 0
(-8000 1675);
DISPLAY 0.680851 (-8000 1675);
DISPLAY INVISIBLE (-8000 1675);
FORCEADD OFFPAGE..3
R 2
(-7725 1525);
FORCEPROP 2 LAST $XR1 186 
J 0
(-8155 1525);
DISPLAY 0.638298 (-8155 1525);
PAINT MONO (-8155 1525);
FORCEPROP 2 LAST $XR0 185 
J 0
(-8035 1525);
DISPLAY 0.638298 (-8035 1525);
PAINT MONO (-8035 1525);
FORCEPROP 2 LAST CDS_LIB standard
J 0
(-7725 1525);
DISPLAY INVISIBLE (-7725 1525);
FORCEPROP 1 LAST OFFPAGE TRUE
J 2
(-8050 1400);
DISPLAY 0.872340 (-8050 1400);
PAINT GREEN (-8050 1400);
DISPLAY INVISIBLE (-8050 1400);
FORCEPROP 1 LAST COMMENT_BODY TRUE
J 2
(-7675 1425);
DISPLAY 0.872340 (-7675 1425);
PAINT GREEN (-7675 1425);
DISPLAY INVISIBLE (-7675 1425);
FORCEPROP 2 LAST PATH I26
J 0
(-8000 1575);
DISPLAY 0.680851 (-8000 1575);
DISPLAY INVISIBLE (-8000 1575);
FORCEADD Q_RES..1
(-6575 1025);
FORCEPROP 1 LAST LOCATION R620
J 0
(-6825 1025);
DISPLAY 0.978723 (-6825 1025);
FORCEPROP 2 LAST SEC 1
J 0
(-6625 1225);
DISPLAY 0.680851 (-6625 1225);
PAINT MONO (-6625 1225);
DISPLAY INVISIBLE (-6625 1225);
FORCEPROP 1 LASTPIN (-6675 1025) $PN 1
J 0
(-6663 1037);
DISPLAY 0.787234 (-6663 1037);
PAINT MONO (-6663 1037);
FORCEPROP 1 LASTPIN (-6475 1025) $PN 2
J 0
(-6513 1037);
DISPLAY 0.787234 (-6513 1037);
PAINT MONO (-6513 1037);
FORCEPROP 1 LAST PACK_TYPE 0201LF
J 0
(-6550 1100);
DISPLAY 0.787234 (-6550 1100);
FORCEPROP 1 LAST MATERIAL CHIP
J 0
(-6750 1100);
DISPLAY 0.787234 (-6750 1100);
FORCEPROP 2 LAST CDS_LIB pure_quanta
J 0
(-6575 1025);
DISPLAY INVISIBLE (-6575 1025);
FORCEPROP 1 LAST TOLERANCE 5%
J 0
(-6750 1150);
DISPLAY 0.787234 (-6750 1150);
DISPLAY INVISIBLE (-6750 1150);
FORCEPROP 1 LAST VALUE 0
J 2
(-6775 1150);
DISPLAY 0.787234 (-6775 1150);
DISPLAY INVISIBLE (-6775 1150);
FORCEPROP 1 LAST WATTAGE 1/20W
J 2
(-6775 1100);
DISPLAY 0.787234 (-6775 1100);
DISPLAY INVISIBLE (-6775 1100);
FORCEPROP 2 LAST SEC_TYPE 0201LF
J 0
(-6625 1225);
DISPLAY 0.680851 (-6625 1225);
DISPLAY INVISIBLE (-6625 1225);
FORCEPROP 1 LAST PATH I27
J 0
(-6625 1175);
DISPLAY 0.978723 (-6625 1175);
PAINT WHITE (-6625 1175);
DISPLAY INVISIBLE (-6625 1175);
FORCEPROP 1 LAST PART_NUMBER CS00001JE10
J 0
(-6625 1150);
DISPLAY 0.808511 (-6625 1150);
DISPLAY INVISIBLE (-6625 1150);
FORCEADD Q_RES..1
(-6575 1175);
FORCEPROP 1 LAST LOCATION R619
J 0
(-6825 1175);
DISPLAY 0.978723 (-6825 1175);
FORCEPROP 2 LAST SEC 1
J 0
(-6625 1375);
DISPLAY 0.680851 (-6625 1375);
PAINT MONO (-6625 1375);
DISPLAY INVISIBLE (-6625 1375);
FORCEPROP 1 LASTPIN (-6675 1175) $PN 1
J 0
(-6663 1187);
DISPLAY 0.787234 (-6663 1187);
PAINT MONO (-6663 1187);
FORCEPROP 1 LASTPIN (-6475 1175) $PN 2
J 0
(-6513 1187);
DISPLAY 0.787234 (-6513 1187);
PAINT MONO (-6513 1187);
FORCEPROP 1 LAST MATERIAL CHIP
J 0
(-6750 1250);
DISPLAY 0.787234 (-6750 1250);
FORCEPROP 1 LAST VALUE 0
J 2
(-6775 1300);
DISPLAY 0.787234 (-6775 1300);
FORCEPROP 1 LAST TOLERANCE 5%
J 0
(-6750 1300);
DISPLAY 0.787234 (-6750 1300);
FORCEPROP 1 LAST WATTAGE 1/20W
J 2
(-6775 1250);
DISPLAY 0.787234 (-6775 1250);
FORCEPROP 1 LAST PACK_TYPE 0201LF
J 0
(-6550 1250);
DISPLAY 0.787234 (-6550 1250);
FORCEPROP 2 LAST CDS_LIB pure_quanta
J 0
(-6575 1175);
DISPLAY INVISIBLE (-6575 1175);
FORCEPROP 0 LAST SEC_TYPE 0201LF
J 0
(-6625 1375);
DISPLAY 0.680851 (-6625 1375);
DISPLAY INVISIBLE (-6625 1375);
FORCEPROP 1 LAST PATH I28
J 0
(-6625 1325);
DISPLAY 0.978723 (-6625 1325);
PAINT WHITE (-6625 1325);
DISPLAY INVISIBLE (-6625 1325);
FORCEPROP 1 LAST PART_NUMBER CS00001JE10
J 0
(-6625 1300);
DISPLAY 0.808511 (-6625 1300);
DISPLAY INVISIBLE (-6625 1300);
FORCEADD Q_RES..1
(-6300 1525);
FORCEPROP 1 LAST LOCATION R692
J 0
(-6550 1550);
DISPLAY 0.978723 (-6550 1550);
FORCEPROP 0 LAST $SEC 1
J 0
(-6450 1600);
DISPLAY 0.680851 (-6450 1600);
PAINT MONO (-6450 1600);
DISPLAY INVISIBLE (-6450 1600);
FORCEPROP 0 LAST CDS_SEC 1
J 0
(-6450 1600);
DISPLAY 0.680851 (-6450 1600);
DISPLAY INVISIBLE (-6450 1600);
FORCEPROP 1 LASTPIN (-6400 1525) $PN 1
J 0
(-6388 1537);
DISPLAY 0.787234 (-6388 1537);
PAINT MONO (-6388 1537);
FORCEPROP 1 LASTPIN (-6200 1525) $PN 2
J 0
(-6238 1537);
DISPLAY 0.787234 (-6238 1537);
PAINT MONO (-6238 1537);
FORCEPROP 2 LAST CDS_LIB pure_quanta
J 0
(-6300 1525);
DISPLAY INVISIBLE (-6300 1525);
FORCEPROP 1 LAST MATERIAL CHIP
J 0
(-6475 1600);
DISPLAY 0.787234 (-6475 1600);
DISPLAY INVISIBLE (-6475 1600);
FORCEPROP 1 LAST WATTAGE 1/20W
J 2
(-6500 1600);
DISPLAY 0.787234 (-6500 1600);
DISPLAY INVISIBLE (-6500 1600);
FORCEPROP 1 LAST PACK_TYPE 0201LF
J 0
(-6275 1600);
DISPLAY 0.787234 (-6275 1600);
DISPLAY INVISIBLE (-6275 1600);
FORCEPROP 1 LAST VALUE 49.9
J 2
(-6500 1650);
DISPLAY 0.787234 (-6500 1650);
DISPLAY INVISIBLE (-6500 1650);
FORCEPROP 1 LAST TOLERANCE 1%
J 0
(-6475 1650);
DISPLAY 0.787234 (-6475 1650);
DISPLAY INVISIBLE (-6475 1650);
FORCEPROP 1 LAST PATH I29
J 0
(-6350 1675);
DISPLAY 0.978723 (-6350 1675);
PAINT WHITE (-6350 1675);
DISPLAY INVISIBLE (-6350 1675);
FORCEPROP 1 LAST PART_NUMBER CS04991FE06
J 0
(-6350 1650);
DISPLAY 0.808511 (-6350 1650);
DISPLAY INVISIBLE (-6350 1650);
FORCEADD Q_RES..1
(-6300 1625);
FORCEPROP 1 LAST LOCATION R691
J 0
(-6550 1650);
DISPLAY 0.978723 (-6550 1650);
FORCEPROP 0 LAST $SEC 1
J 0
(-6350 1800);
DISPLAY 0.680851 (-6350 1800);
PAINT MONO (-6350 1800);
DISPLAY INVISIBLE (-6350 1800);
FORCEPROP 0 LAST CDS_SEC 1
J 0
(-6350 1800);
DISPLAY 0.680851 (-6350 1800);
DISPLAY INVISIBLE (-6350 1800);
FORCEPROP 1 LASTPIN (-6400 1625) $PN 1
J 0
(-6388 1637);
DISPLAY 0.787234 (-6388 1637);
PAINT MONO (-6388 1637);
FORCEPROP 1 LASTPIN (-6200 1625) $PN 2
J 0
(-6238 1637);
DISPLAY 0.787234 (-6238 1637);
PAINT MONO (-6238 1637);
FORCEPROP 1 LAST MATERIAL CHIP
J 0
(-6475 1700);
DISPLAY 0.787234 (-6475 1700);
FORCEPROP 1 LAST WATTAGE 1/20W
J 2
(-6500 1700);
DISPLAY 0.787234 (-6500 1700);
FORCEPROP 1 LAST PACK_TYPE 0201LF
J 0
(-6275 1700);
DISPLAY 0.787234 (-6275 1700);
FORCEPROP 1 LAST VALUE 49.9
J 2
(-6500 1750);
DISPLAY 0.787234 (-6500 1750);
FORCEPROP 1 LAST TOLERANCE 1%
J 0
(-6475 1750);
DISPLAY 0.787234 (-6475 1750);
FORCEPROP 2 LAST CDS_LIB pure_quanta
J 0
(-6300 1625);
DISPLAY INVISIBLE (-6300 1625);
FORCEPROP 1 LAST PATH I30
J 0
(-6350 1775);
DISPLAY 0.978723 (-6350 1775);
PAINT WHITE (-6350 1775);
DISPLAY INVISIBLE (-6350 1775);
FORCEPROP 1 LAST PART_NUMBER CS04991FE06
J 0
(-6350 1750);
DISPLAY 0.808511 (-6350 1750);
DISPLAY INVISIBLE (-6350 1750);
FORCEADD OFFPAGE..3
R 2
(-7625 2775);
FORCEPROP 2 LAST $XR0 184 
J 0
(-7905 2775);
DISPLAY 0.638298 (-7905 2775);
PAINT MONO (-7905 2775);
FORCEPROP 2 LAST CDS_LIB standard
J 0
(-7625 2775);
DISPLAY INVISIBLE (-7625 2775);
FORCEPROP 1 LAST OFFPAGE TRUE
J 2
(-7950 2650);
DISPLAY 0.872340 (-7950 2650);
PAINT GREEN (-7950 2650);
DISPLAY INVISIBLE (-7950 2650);
FORCEPROP 1 LAST COMMENT_BODY TRUE
J 2
(-7575 2675);
DISPLAY 0.872340 (-7575 2675);
PAINT GREEN (-7575 2675);
DISPLAY INVISIBLE (-7575 2675);
FORCEPROP 2 LAST PATH I31
J 0
(-7925 2825);
DISPLAY 0.680851 (-7925 2825);
DISPLAY INVISIBLE (-7925 2825);
FORCEADD OFFPAGE..1
(-7625 2875);
FORCEPROP 2 LAST $XR0 184 
J 0
(-7877 2875);
DISPLAY 0.638298 (-7877 2875);
PAINT MONO (-7877 2875);
FORCEPROP 2 LAST CDS_LIB standard
J 0
(-7625 2875);
DISPLAY INVISIBLE (-7625 2875);
FORCEPROP 1 LAST OFFPAGE TRUE
J 0
(-7300 2750);
DISPLAY 0.872340 (-7300 2750);
DISPLAY INVISIBLE (-7300 2750);
FORCEPROP 1 LAST COMMENT_BODY TRUE
J 0
(-7500 2775);
DISPLAY 0.872340 (-7500 2775);
PAINT GREEN (-7500 2775);
DISPLAY INVISIBLE (-7500 2775);
FORCEPROP 2 LAST PATH I32
J 0
(-7875 2925);
DISPLAY 0.680851 (-7875 2925);
DISPLAY INVISIBLE (-7875 2925);
FORCEADD OFFPAGE..5
R 2
(-7775 3875);
FORCEPROP 2 LAST $XR0 343 
J 0
(-7586 3875);
DISPLAY 0.638298 (-7586 3875);
PAINT MONO (-7586 3875);
FORCEPROP 2 LAST CDS_LIB standard
J 0
(-7775 3875);
DISPLAY INVISIBLE (-7775 3875);
FORCEPROP 1 LAST OFFPAGE TRUE
J 2
(-8100 3750);
DISPLAY 0.872340 (-8100 3750);
PAINT GREEN (-8100 3750);
DISPLAY INVISIBLE (-8100 3750);
FORCEPROP 1 LAST COMMENT_BODY TRUE
J 2
(-7875 3800);
DISPLAY 0.872340 (-7875 3800);
PAINT GREEN (-7875 3800);
DISPLAY INVISIBLE (-7875 3800);
FORCEPROP 2 LAST PATH I33
J 0
(-7575 3925);
DISPLAY 0.680851 (-7575 3925);
DISPLAY INVISIBLE (-7575 3925);
FORCEADD Q_RES..1
(-6325 2875);
FORCEPROP 1 LAST LOCATION R872
J 0
(-6575 2900);
DISPLAY 0.978723 (-6575 2900);
FORCEPROP 0 LAST $SEC 1
J 0
(-6375 3050);
DISPLAY 0.680851 (-6375 3050);
PAINT MONO (-6375 3050);
DISPLAY INVISIBLE (-6375 3050);
FORCEPROP 0 LAST CDS_SEC 1
J 0
(-6375 3050);
DISPLAY 0.680851 (-6375 3050);
DISPLAY INVISIBLE (-6375 3050);
FORCEPROP 1 LASTPIN (-6425 2875) $PN 1
J 0
(-6413 2887);
DISPLAY 0.787234 (-6413 2887);
PAINT MONO (-6413 2887);
FORCEPROP 1 LASTPIN (-6225 2875) $PN 2
J 0
(-6263 2887);
DISPLAY 0.787234 (-6263 2887);
PAINT MONO (-6263 2887);
FORCEPROP 1 LAST TOLERANCE 5%
J 0
(-6500 3000);
DISPLAY 0.787234 (-6500 3000);
FORCEPROP 1 LAST WATTAGE 1/20W
J 2
(-6525 2950);
DISPLAY 0.787234 (-6525 2950);
FORCEPROP 1 LAST MATERIAL CHIP
J 0
(-6500 2950);
DISPLAY 0.787234 (-6500 2950);
FORCEPROP 1 LAST VALUE 0
J 2
(-6525 3000);
DISPLAY 0.787234 (-6525 3000);
FORCEPROP 1 LAST PACK_TYPE 0201LF
J 0
(-6300 2950);
DISPLAY 0.787234 (-6300 2950);
FORCEPROP 2 LAST CDS_LIB pure_quanta
J 0
(-6325 2875);
DISPLAY INVISIBLE (-6325 2875);
FORCEPROP 1 LAST PATH I34
J 0
(-6375 3025);
DISPLAY 0.978723 (-6375 3025);
PAINT WHITE (-6375 3025);
DISPLAY INVISIBLE (-6375 3025);
FORCEPROP 1 LAST PART_NUMBER CS00001JE10
J 0
(-6375 3000);
DISPLAY 0.808511 (-6375 3000);
DISPLAY INVISIBLE (-6375 3000);
FORCEADD Q_RES..1
(-6325 2775);
FORCEPROP 1 LAST LOCATION R873
J 0
(-6575 2800);
DISPLAY 0.978723 (-6575 2800);
FORCEPROP 0 LAST $SEC 1
J 0
(-6575 2850);
DISPLAY 0.680851 (-6575 2850);
PAINT MONO (-6575 2850);
DISPLAY INVISIBLE (-6575 2850);
FORCEPROP 0 LAST CDS_SEC 1
J 0
(-6575 2850);
DISPLAY 0.680851 (-6575 2850);
DISPLAY INVISIBLE (-6575 2850);
FORCEPROP 1 LASTPIN (-6425 2775) $PN 1
J 0
(-6413 2787);
DISPLAY 0.787234 (-6413 2787);
PAINT MONO (-6413 2787);
FORCEPROP 1 LASTPIN (-6225 2775) $PN 2
J 0
(-6263 2787);
DISPLAY 0.787234 (-6263 2787);
PAINT MONO (-6263 2787);
FORCEPROP 1 LAST WATTAGE 1/20W
J 2
(-6525 2850);
DISPLAY 0.787234 (-6525 2850);
DISPLAY INVISIBLE (-6525 2850);
FORCEPROP 1 LAST VALUE 0
J 2
(-6525 2900);
DISPLAY 0.787234 (-6525 2900);
DISPLAY INVISIBLE (-6525 2900);
FORCEPROP 1 LAST TOLERANCE 5%
J 0
(-6500 2900);
DISPLAY 0.787234 (-6500 2900);
DISPLAY INVISIBLE (-6500 2900);
FORCEPROP 1 LAST MATERIAL CHIP
J 0
(-6500 2850);
DISPLAY 0.787234 (-6500 2850);
DISPLAY INVISIBLE (-6500 2850);
FORCEPROP 1 LAST PACK_TYPE 0201LF
J 0
(-6300 2850);
DISPLAY 0.787234 (-6300 2850);
DISPLAY INVISIBLE (-6300 2850);
FORCEPROP 2 LAST CDS_LIB pure_quanta
J 0
(-6325 2775);
DISPLAY INVISIBLE (-6325 2775);
FORCEPROP 1 LAST PATH I35
J 0
(-6375 2925);
DISPLAY 0.978723 (-6375 2925);
PAINT WHITE (-6375 2925);
DISPLAY INVISIBLE (-6375 2925);
FORCEPROP 1 LAST PART_NUMBER CS00001JE10
J 0
(-6375 2900);
DISPLAY 0.808511 (-6375 2900);
DISPLAY INVISIBLE (-6375 2900);
FORCEADD Q_RES..2
(-6125 700);
FORCEPROP 1 LAST LOCATION R640
J 0
(-6080 825);
DISPLAY 0.978723 (-6080 825);
FORCEPROP 0 LAST $SEC 1
J 0
(-6075 875);
DISPLAY 0.680851 (-6075 875);
PAINT MONO (-6075 875);
DISPLAY INVISIBLE (-6075 875);
FORCEPROP 0 LAST CDS_SEC 1
J 0
(-6075 875);
DISPLAY 0.680851 (-6075 875);
DISPLAY INVISIBLE (-6075 875);
FORCEPROP 1 LASTPIN (-6125 800) $PN 1
J 0
(-6120 762);
DISPLAY 0.787234 (-6120 762);
PAINT MONO (-6120 762);
FORCEPROP 1 LASTPIN (-6125 600) $PN 2
J 0
(-6120 610);
DISPLAY 0.787234 (-6120 610);
PAINT MONO (-6120 610);
FORCEPROP 1 LAST PACK_TYPE 0201LF
J 0
(-6085 525);
DISPLAY 0.978723 (-6085 525);
FORCEPROP 1 LAST TOLERANCE 1%
J 0
(-6080 725);
DISPLAY 0.978723 (-6080 725);
FORCEPROP 1 LAST MATERIAL EMPTY
J 0
(-6085 625);
DISPLAY 0.978723 (-6085 625);
FORCEPROP 1 LAST WATTAGE 1/20W
J 0
(-6085 675);
DISPLAY 0.978723 (-6085 675);
FORCEPROP 1 LAST VALUE 51.1
J 0
(-6080 775);
DISPLAY 0.978723 (-6080 775);
FORCEPROP 2 LAST CDS_LIB pure_quanta
J 0
(-6125 700);
DISPLAY INVISIBLE (-6125 700);
FORCEPROP 1 LAST PATH I36
J 0
(-6075 875);
DISPLAY 0.978723 (-6075 875);
PAINT WHITE (-6075 875);
DISPLAY INVISIBLE (-6075 875);
FORCEPROP 1 LAST PART_NUMBER CS05111FE00
J 0
(-6085 575);
DISPLAY 0.978723 (-6085 575);
DISPLAY INVISIBLE (-6085 575);
FORCEADD OFFPAGE..1
(-5950 2625);
FORCEPROP 2 LAST $XR0 343 
J 0
(-6202 2625);
DISPLAY 0.638298 (-6202 2625);
PAINT MONO (-6202 2625);
FORCEPROP 2 LAST CDS_LIB standard
J 0
(-5950 2625);
DISPLAY INVISIBLE (-5950 2625);
FORCEPROP 1 LAST OFFPAGE TRUE
J 0
(-5625 2500);
DISPLAY 0.872340 (-5625 2500);
DISPLAY INVISIBLE (-5625 2500);
FORCEPROP 1 LAST COMMENT_BODY TRUE
J 0
(-5825 2525);
DISPLAY 0.872340 (-5825 2525);
PAINT GREEN (-5825 2525);
DISPLAY INVISIBLE (-5825 2525);
FORCEPROP 2 LAST PATH I37
J 0
(-6200 2675);
DISPLAY 0.680851 (-6200 2675);
DISPLAY INVISIBLE (-6200 2675);
FORCEADD OFFPAGE..1
(-5950 2525);
FORCEPROP 2 LAST $XR0 343 
J 0
(-6202 2525);
DISPLAY 0.638298 (-6202 2525);
PAINT MONO (-6202 2525);
FORCEPROP 2 LAST CDS_LIB standard
J 0
(-5950 2525);
DISPLAY INVISIBLE (-5950 2525);
FORCEPROP 1 LAST OFFPAGE TRUE
J 0
(-5625 2400);
DISPLAY 0.872340 (-5625 2400);
DISPLAY INVISIBLE (-5625 2400);
FORCEPROP 1 LAST COMMENT_BODY TRUE
J 0
(-5825 2425);
DISPLAY 0.872340 (-5825 2425);
PAINT GREEN (-5825 2425);
DISPLAY INVISIBLE (-5825 2425);
FORCEPROP 2 LAST PATH I38
J 0
(-6200 2575);
DISPLAY 0.680851 (-6200 2575);
DISPLAY INVISIBLE (-6200 2575);
FORCEADD OFFPAGE..1
(-5950 2425);
FORCEPROP 2 LAST $XR0 343 
J 0
(-6202 2425);
DISPLAY 0.638298 (-6202 2425);
PAINT MONO (-6202 2425);
FORCEPROP 2 LAST CDS_LIB standard
J 0
(-5950 2425);
DISPLAY INVISIBLE (-5950 2425);
FORCEPROP 1 LAST OFFPAGE TRUE
J 0
(-5625 2300);
DISPLAY 0.872340 (-5625 2300);
DISPLAY INVISIBLE (-5625 2300);
FORCEPROP 1 LAST COMMENT_BODY TRUE
J 0
(-5825 2325);
DISPLAY 0.872340 (-5825 2325);
PAINT GREEN (-5825 2325);
DISPLAY INVISIBLE (-5825 2325);
FORCEPROP 2 LAST PATH I39
J 0
(-6200 2475);
DISPLAY 0.680851 (-6200 2475);
DISPLAY INVISIBLE (-6200 2475);
FORCEADD OFFPAGE..1
(-6000 3225);
FORCEPROP 2 LAST $XR0 343 
J 0
(-6282 3225);
DISPLAY 0.638298 (-6282 3225);
PAINT MONO (-6282 3225);
FORCEPROP 2 LAST CDS_LIB standard
J 0
(-6000 3225);
DISPLAY INVISIBLE (-6000 3225);
FORCEPROP 1 LAST OFFPAGE TRUE
J 0
(-5675 3100);
DISPLAY 0.872340 (-5675 3100);
DISPLAY INVISIBLE (-5675 3100);
FORCEPROP 1 LAST COMMENT_BODY TRUE
J 0
(-5875 3125);
DISPLAY 0.872340 (-5875 3125);
PAINT GREEN (-5875 3125);
DISPLAY INVISIBLE (-5875 3125);
FORCEPROP 2 LAST PATH I40
J 0
(-6250 3275);
DISPLAY 0.680851 (-6250 3275);
DISPLAY INVISIBLE (-6250 3275);
FORCEADD OFFPAGE..1
(-6000 3325);
FORCEPROP 2 LAST $XR0 343 
J 0
(-6282 3325);
DISPLAY 0.638298 (-6282 3325);
PAINT MONO (-6282 3325);
FORCEPROP 2 LAST CDS_LIB standard
J 0
(-6000 3325);
DISPLAY INVISIBLE (-6000 3325);
FORCEPROP 1 LAST OFFPAGE TRUE
J 0
(-5675 3200);
DISPLAY 0.872340 (-5675 3200);
DISPLAY INVISIBLE (-5675 3200);
FORCEPROP 1 LAST COMMENT_BODY TRUE
J 0
(-5875 3225);
DISPLAY 0.872340 (-5875 3225);
PAINT GREEN (-5875 3225);
DISPLAY INVISIBLE (-5875 3225);
FORCEPROP 2 LAST PATH I41
J 0
(-6250 3375);
DISPLAY 0.680851 (-6250 3375);
DISPLAY INVISIBLE (-6250 3375);
FORCEADD Q_RES..2
(-8300 5025);
FORCEPROP 1 LAST LOCATION R879
J 0
(-8255 5150);
DISPLAY 0.787234 (-8255 5150);
FORCEPROP 0 LAST $SEC 1
J 0
(-8250 5200);
DISPLAY 0.680851 (-8250 5200);
PAINT MONO (-8250 5200);
DISPLAY INVISIBLE (-8250 5200);
FORCEPROP 0 LAST CDS_SEC 1
J 0
(-8250 5200);
DISPLAY 0.680851 (-8250 5200);
DISPLAY INVISIBLE (-8250 5200);
FORCEPROP 1 LASTPIN (-8300 5125) $PN 1
J 0
(-8295 5087);
DISPLAY 0.787234 (-8295 5087);
PAINT MONO (-8295 5087);
FORCEPROP 1 LASTPIN (-8300 4925) $PN 2
J 0
(-8295 4935);
DISPLAY 0.787234 (-8295 4935);
PAINT MONO (-8295 4935);
FORCEPROP 1 LAST MATERIAL CHIP
J 0
(-8260 4950);
DISPLAY 0.787234 (-8260 4950);
FORCEPROP 1 LAST PACK_TYPE 0201LF
J 0
(-8260 4850);
DISPLAY 0.787234 (-8260 4850);
FORCEPROP 1 LAST WATTAGE 1/20W
J 0
(-8260 5000);
DISPLAY 0.787234 (-8260 5000);
FORCEPROP 1 LAST TOLERANCE 5%
J 0
(-8255 5050);
DISPLAY 0.787234 (-8255 5050);
FORCEPROP 1 LAST VALUE 4.7K
J 0
(-8255 5100);
DISPLAY 0.787234 (-8255 5100);
FORCEPROP 2 LAST CDS_LIB pure_quanta
J 0
(-8300 5025);
DISPLAY INVISIBLE (-8300 5025);
FORCEPROP 1 LAST PATH I42
J 0
(-8250 5200);
DISPLAY 0.978723 (-8250 5200);
PAINT WHITE (-8250 5200);
DISPLAY INVISIBLE (-8250 5200);
FORCEPROP 1 LAST PART_NUMBER CS24701JE04
J 0
(-8260 4900);
DISPLAY 0.978723 (-8260 4900);
DISPLAY INVISIBLE (-8260 4900);
FORCEADD Q_RES..2
(-8000 5000);
FORCEPROP 1 LAST LOCATION R881
J 0
(-7955 5125);
DISPLAY 0.787234 (-7955 5125);
FORCEPROP 0 LAST $SEC 1
J 0
(-7950 5175);
DISPLAY 0.680851 (-7950 5175);
PAINT MONO (-7950 5175);
DISPLAY INVISIBLE (-7950 5175);
FORCEPROP 0 LAST CDS_SEC 1
J 0
(-7950 5175);
DISPLAY 0.680851 (-7950 5175);
DISPLAY INVISIBLE (-7950 5175);
FORCEPROP 1 LASTPIN (-8000 5100) $PN 1
J 0
(-7995 5062);
DISPLAY 0.787234 (-7995 5062);
PAINT MONO (-7995 5062);
FORCEPROP 1 LASTPIN (-8000 4900) $PN 2
J 0
(-7995 4910);
DISPLAY 0.787234 (-7995 4910);
PAINT MONO (-7995 4910);
FORCEPROP 1 LAST WATTAGE 1/20W
J 0
(-7960 4975);
DISPLAY 0.787234 (-7960 4975);
FORCEPROP 1 LAST MATERIAL CHIP
J 0
(-7960 4925);
DISPLAY 0.787234 (-7960 4925);
FORCEPROP 1 LAST PACK_TYPE 0201LF
J 0
(-7960 4825);
DISPLAY 0.787234 (-7960 4825);
FORCEPROP 1 LAST TOLERANCE 5%
J 0
(-7955 5025);
DISPLAY 0.787234 (-7955 5025);
FORCEPROP 1 LAST VALUE 4.7K
J 0
(-7955 5075);
DISPLAY 0.787234 (-7955 5075);
FORCEPROP 2 LAST CDS_LIB pure_quanta
J 0
(-8000 5000);
DISPLAY INVISIBLE (-8000 5000);
FORCEPROP 1 LAST PATH I43
J 0
(-7950 5175);
DISPLAY 0.978723 (-7950 5175);
PAINT WHITE (-7950 5175);
DISPLAY INVISIBLE (-7950 5175);
FORCEPROP 1 LAST PART_NUMBER CS24701JE04
J 0
(-7960 4875);
DISPLAY 0.978723 (-7960 4875);
DISPLAY INVISIBLE (-7960 4875);
FORCEADD UNIVERSAL_GND..1
(-7400 4525);
FORCEPROP 3 LASTPIN (-7400 4575) SIG_NAME GND\g
J 0
(-7390 4585);
DISPLAY 0.659574 (-7390 4585);
PAINT MONO (-7390 4585);
DISPLAY INVISIBLE (-7390 4585);
FORCEPROP 2 LAST CDS_LIB pure_quanta_power
J 0
(-7400 4525);
DISPLAY INVISIBLE (-7400 4525);
FORCEPROP 1 LAST HDL_POWER GND
J 1
(-7375 4450);
DISPLAY 0.872340 (-7375 4450);
PAINT GREEN (-7375 4450);
DISPLAY INVISIBLE (-7375 4450);
FORCEPROP 1 LAST PATH I44
J 0
(-7325 4525);
DISPLAY 0.872340 (-7325 4525);
PAINT AQUA (-7325 4525);
DISPLAY INVISIBLE (-7325 4525);
FORCEADD Q_RES..2
(-7700 5000);
FORCEPROP 1 LAST LOCATION R883
J 0
(-7655 5125);
DISPLAY 0.787234 (-7655 5125);
FORCEPROP 0 LAST $SEC 1
J 0
(-7650 5175);
DISPLAY 0.680851 (-7650 5175);
PAINT MONO (-7650 5175);
DISPLAY INVISIBLE (-7650 5175);
FORCEPROP 0 LAST CDS_SEC 1
J 0
(-7650 5175);
DISPLAY 0.680851 (-7650 5175);
DISPLAY INVISIBLE (-7650 5175);
FORCEPROP 1 LASTPIN (-7700 5100) $PN 1
J 0
(-7695 5062);
DISPLAY 0.787234 (-7695 5062);
PAINT MONO (-7695 5062);
FORCEPROP 1 LASTPIN (-7700 4900) $PN 2
J 0
(-7695 4910);
DISPLAY 0.787234 (-7695 4910);
PAINT MONO (-7695 4910);
FORCEPROP 1 LAST WATTAGE 1/20W
J 0
(-7660 4975);
DISPLAY 0.787234 (-7660 4975);
FORCEPROP 1 LAST TOLERANCE 5%
J 0
(-7655 5025);
DISPLAY 0.787234 (-7655 5025);
FORCEPROP 1 LAST VALUE 4.7K
J 0
(-7655 5075);
DISPLAY 0.787234 (-7655 5075);
FORCEPROP 1 LAST PACK_TYPE 0201LF
J 0
(-7660 4825);
DISPLAY 0.787234 (-7660 4825);
FORCEPROP 1 LAST MATERIAL CHIP
J 0
(-7660 4925);
DISPLAY 0.787234 (-7660 4925);
FORCEPROP 2 LAST CDS_LIB pure_quanta
J 0
(-7700 5000);
DISPLAY INVISIBLE (-7700 5000);
FORCEPROP 1 LAST PATH I45
J 0
(-7650 5175);
DISPLAY 0.978723 (-7650 5175);
PAINT WHITE (-7650 5175);
DISPLAY INVISIBLE (-7650 5175);
FORCEPROP 1 LAST PART_NUMBER CS24701JE04
J 0
(-7660 4875);
DISPLAY 0.787234 (-7660 4875);
DISPLAY INVISIBLE (-7660 4875);
FORCEADD Q_RES..2
(-7400 4975);
FORCEPROP 1 LAST LOCATION R884
J 0
(-7355 5100);
DISPLAY 0.787234 (-7355 5100);
FORCEPROP 0 LAST $SEC 1
J 0
(-7350 5150);
DISPLAY 0.680851 (-7350 5150);
PAINT MONO (-7350 5150);
DISPLAY INVISIBLE (-7350 5150);
FORCEPROP 0 LAST CDS_SEC 1
J 0
(-7350 5150);
DISPLAY 0.680851 (-7350 5150);
DISPLAY INVISIBLE (-7350 5150);
FORCEPROP 1 LASTPIN (-7400 5075) $PN 1
J 0
(-7395 5037);
DISPLAY 0.787234 (-7395 5037);
PAINT MONO (-7395 5037);
FORCEPROP 1 LASTPIN (-7400 4875) $PN 2
J 0
(-7395 4885);
DISPLAY 0.787234 (-7395 4885);
PAINT MONO (-7395 4885);
FORCEPROP 1 LAST PACK_TYPE 0201LF
J 0
(-7360 4800);
DISPLAY 0.787234 (-7360 4800);
FORCEPROP 1 LAST TOLERANCE 5%
J 0
(-7355 5000);
DISPLAY 0.787234 (-7355 5000);
FORCEPROP 1 LAST VALUE 4.7K
J 0
(-7355 5050);
DISPLAY 0.787234 (-7355 5050);
FORCEPROP 1 LAST MATERIAL CHIP
J 0
(-7360 4900);
DISPLAY 0.787234 (-7360 4900);
FORCEPROP 1 LAST WATTAGE 1/20W
J 0
(-7360 4950);
DISPLAY 0.787234 (-7360 4950);
FORCEPROP 2 LAST CDS_LIB pure_quanta
J 0
(-7400 4975);
DISPLAY INVISIBLE (-7400 4975);
FORCEPROP 1 LAST PATH I46
J 0
(-7350 5150);
DISPLAY 0.978723 (-7350 5150);
PAINT WHITE (-7350 5150);
DISPLAY INVISIBLE (-7350 5150);
FORCEPROP 1 LAST PART_NUMBER CS24701JE04
J 0
(-7360 4850);
DISPLAY 0.638298 (-7360 4850);
DISPLAY INVISIBLE (-7360 4850);
FORCEADD Q_RES..2
(-8300 5975);
FORCEPROP 1 LAST LOCATION R878
J 0
(-8255 6100);
DISPLAY 0.787234 (-8255 6100);
FORCEPROP 0 LAST $SEC 1
J 0
(-8250 6150);
DISPLAY 0.680851 (-8250 6150);
PAINT MONO (-8250 6150);
DISPLAY INVISIBLE (-8250 6150);
FORCEPROP 0 LAST CDS_SEC 1
J 0
(-8250 6150);
DISPLAY 0.680851 (-8250 6150);
DISPLAY INVISIBLE (-8250 6150);
FORCEPROP 1 LASTPIN (-8300 6075) $PN 1
J 0
(-8295 6037);
DISPLAY 0.787234 (-8295 6037);
PAINT MONO (-8295 6037);
FORCEPROP 1 LASTPIN (-8300 5875) $PN 2
J 0
(-8295 5885);
DISPLAY 0.787234 (-8295 5885);
PAINT MONO (-8295 5885);
FORCEPROP 1 LAST VALUE 4.7K
J 0
(-8255 6050);
DISPLAY 0.787234 (-8255 6050);
FORCEPROP 1 LAST WATTAGE 1/20W
J 0
(-8260 5950);
DISPLAY 0.787234 (-8260 5950);
FORCEPROP 1 LAST MATERIAL EMPTY
J 0
(-8260 5900);
DISPLAY 0.787234 (-8260 5900);
FORCEPROP 1 LAST PACK_TYPE 0201LF
J 0
(-8250 5825);
DISPLAY 0.787234 (-8250 5825);
FORCEPROP 1 LAST TOLERANCE 5%
J 0
(-8255 6000);
DISPLAY 0.787234 (-8255 6000);
FORCEPROP 2 LAST CDS_LIB pure_quanta
J 0
(-8300 5975);
DISPLAY INVISIBLE (-8300 5975);
FORCEPROP 1 LAST PATH I47
J 0
(-8250 6150);
DISPLAY 0.978723 (-8250 6150);
PAINT WHITE (-8250 6150);
DISPLAY INVISIBLE (-8250 6150);
FORCEPROP 1 LAST PART_NUMBER CS24701JE04
J 0
(-8260 5850);
DISPLAY 0.978723 (-8260 5850);
DISPLAY INVISIBLE (-8260 5850);
FORCEADD Q_RES..2
(-8000 5925);
FORCEPROP 1 LAST LOCATION R880
J 0
(-7955 6050);
DISPLAY 0.787234 (-7955 6050);
FORCEPROP 0 LAST $SEC 1
J 0
(-7950 6100);
DISPLAY 0.680851 (-7950 6100);
PAINT MONO (-7950 6100);
DISPLAY INVISIBLE (-7950 6100);
FORCEPROP 0 LAST CDS_SEC 1
J 0
(-7950 6100);
DISPLAY 0.680851 (-7950 6100);
DISPLAY INVISIBLE (-7950 6100);
FORCEPROP 1 LASTPIN (-8000 6025) $PN 1
J 0
(-7995 5987);
DISPLAY 0.787234 (-7995 5987);
PAINT MONO (-7995 5987);
FORCEPROP 1 LASTPIN (-8000 5825) $PN 2
J 0
(-7995 5835);
DISPLAY 0.787234 (-7995 5835);
PAINT MONO (-7995 5835);
FORCEPROP 1 LAST MATERIAL EMPTY
J 0
(-7960 5850);
DISPLAY 0.787234 (-7960 5850);
FORCEPROP 1 LAST PACK_TYPE 0201LF
J 0
(-7950 5775);
DISPLAY 0.787234 (-7950 5775);
FORCEPROP 1 LAST VALUE 4.7K
J 0
(-7955 6000);
DISPLAY 0.787234 (-7955 6000);
FORCEPROP 1 LAST TOLERANCE 5%
J 0
(-7955 5950);
DISPLAY 0.787234 (-7955 5950);
FORCEPROP 1 LAST WATTAGE 1/20W
J 0
(-7960 5900);
DISPLAY 0.787234 (-7960 5900);
FORCEPROP 2 LAST CDS_LIB pure_quanta
J 0
(-8000 5925);
DISPLAY INVISIBLE (-8000 5925);
FORCEPROP 1 LAST PATH I48
J 0
(-7950 6100);
DISPLAY 0.978723 (-7950 6100);
PAINT WHITE (-7950 6100);
DISPLAY INVISIBLE (-7950 6100);
FORCEPROP 1 LAST PART_NUMBER CS24701JE04
J 0
(-7960 5800);
DISPLAY 0.978723 (-7960 5800);
DISPLAY INVISIBLE (-7960 5800);
FORCEADD Q_RES..2
(-7700 5950);
FORCEPROP 1 LAST LOCATION R882
J 0
(-7655 6075);
DISPLAY 0.787234 (-7655 6075);
FORCEPROP 0 LAST $SEC 1
J 0
(-7650 6125);
DISPLAY 0.680851 (-7650 6125);
PAINT MONO (-7650 6125);
DISPLAY INVISIBLE (-7650 6125);
FORCEPROP 0 LAST CDS_SEC 1
J 0
(-7650 6125);
DISPLAY 0.680851 (-7650 6125);
DISPLAY INVISIBLE (-7650 6125);
FORCEPROP 1 LASTPIN (-7700 6050) $PN 1
J 0
(-7695 6012);
DISPLAY 0.787234 (-7695 6012);
PAINT MONO (-7695 6012);
FORCEPROP 1 LASTPIN (-7700 5850) $PN 2
J 0
(-7695 5860);
DISPLAY 0.787234 (-7695 5860);
PAINT MONO (-7695 5860);
FORCEPROP 1 LAST TOLERANCE 5%
J 0
(-7655 5975);
DISPLAY 0.787234 (-7655 5975);
FORCEPROP 1 LAST PACK_TYPE 0201LF
J 0
(-7660 5775);
DISPLAY 0.787234 (-7660 5775);
FORCEPROP 1 LAST MATERIAL EMPTY
J 0
(-7660 5875);
DISPLAY 0.787234 (-7660 5875);
FORCEPROP 1 LAST WATTAGE 1/20W
J 0
(-7660 5925);
DISPLAY 0.787234 (-7660 5925);
FORCEPROP 1 LAST VALUE 4.7K
J 0
(-7655 6025);
DISPLAY 0.787234 (-7655 6025);
FORCEPROP 2 LAST CDS_LIB pure_quanta
J 0
(-7700 5950);
DISPLAY INVISIBLE (-7700 5950);
FORCEPROP 1 LAST PATH I49
J 0
(-7650 6125);
DISPLAY 0.978723 (-7650 6125);
PAINT WHITE (-7650 6125);
DISPLAY INVISIBLE (-7650 6125);
FORCEPROP 1 LAST PART_NUMBER CS24701JE04
J 0
(-7660 5825);
DISPLAY 0.787234 (-7660 5825);
DISPLAY INVISIBLE (-7660 5825);
FORCEADD Q_RES..2
(-7400 5975);
FORCEPROP 1 LAST LOCATION R871
J 0
(-7355 6100);
DISPLAY 0.787234 (-7355 6100);
FORCEPROP 0 LAST $SEC 1
J 0
(-7350 6150);
DISPLAY 0.680851 (-7350 6150);
PAINT MONO (-7350 6150);
DISPLAY INVISIBLE (-7350 6150);
FORCEPROP 0 LAST CDS_SEC 1
J 0
(-7350 6150);
DISPLAY 0.680851 (-7350 6150);
DISPLAY INVISIBLE (-7350 6150);
FORCEPROP 1 LASTPIN (-7400 6075) $PN 1
J 0
(-7395 6037);
DISPLAY 0.787234 (-7395 6037);
PAINT MONO (-7395 6037);
FORCEPROP 1 LASTPIN (-7400 5875) $PN 2
J 0
(-7395 5885);
DISPLAY 0.787234 (-7395 5885);
PAINT MONO (-7395 5885);
FORCEPROP 1 LAST PACK_TYPE 0201LF
J 0
(-7350 5800);
DISPLAY 0.787234 (-7350 5800);
FORCEPROP 1 LAST VALUE 4.7K
J 0
(-7355 6050);
DISPLAY 0.787234 (-7355 6050);
FORCEPROP 1 LAST TOLERANCE 5%
J 0
(-7355 6000);
DISPLAY 0.787234 (-7355 6000);
FORCEPROP 1 LAST MATERIAL EMPTY
J 0
(-7360 5900);
DISPLAY 0.787234 (-7360 5900);
FORCEPROP 1 LAST WATTAGE 1/20W
J 0
(-7360 5950);
DISPLAY 0.787234 (-7360 5950);
FORCEPROP 2 LAST CDS_LIB pure_quanta
J 0
(-7400 5975);
DISPLAY INVISIBLE (-7400 5975);
FORCEPROP 1 LAST PATH I50
J 0
(-7350 6150);
DISPLAY 0.978723 (-7350 6150);
PAINT WHITE (-7350 6150);
DISPLAY INVISIBLE (-7350 6150);
FORCEPROP 1 LAST PART_NUMBER CS24701JE04
J 0
(-7350 5850);
DISPLAY 0.638298 (-7350 5850);
DISPLAY INVISIBLE (-7350 5850);
FORCEADD OFFPAGE..5
R 2
(-6350 5375);
FORCEPROP 2 LAST $XR0 343 
J 0
(-6161 5375);
DISPLAY 0.638298 (-6161 5375);
PAINT MONO (-6161 5375);
FORCEPROP 2 LAST CDS_LIB standard
J 0
(-6350 5375);
DISPLAY INVISIBLE (-6350 5375);
FORCEPROP 1 LAST OFFPAGE TRUE
J 2
(-6675 5250);
DISPLAY 0.872340 (-6675 5250);
PAINT GREEN (-6675 5250);
DISPLAY INVISIBLE (-6675 5250);
FORCEPROP 1 LAST COMMENT_BODY TRUE
J 2
(-6450 5300);
DISPLAY 0.872340 (-6450 5300);
PAINT GREEN (-6450 5300);
DISPLAY INVISIBLE (-6450 5300);
FORCEPROP 2 LAST PATH I51
J 0
(-6150 5425);
DISPLAY 0.680851 (-6150 5425);
DISPLAY INVISIBLE (-6150 5425);
FORCEADD OFFPAGE..5
R 2
(-6350 5450);
FORCEPROP 2 LAST $XR0 343 
J 0
(-6161 5450);
DISPLAY 0.638298 (-6161 5450);
PAINT MONO (-6161 5450);
FORCEPROP 2 LAST CDS_LIB standard
J 0
(-6350 5450);
DISPLAY INVISIBLE (-6350 5450);
FORCEPROP 1 LAST OFFPAGE TRUE
J 2
(-6675 5325);
DISPLAY 0.872340 (-6675 5325);
PAINT GREEN (-6675 5325);
DISPLAY INVISIBLE (-6675 5325);
FORCEPROP 1 LAST COMMENT_BODY TRUE
J 2
(-6450 5375);
DISPLAY 0.872340 (-6450 5375);
PAINT GREEN (-6450 5375);
DISPLAY INVISIBLE (-6450 5375);
FORCEPROP 2 LAST PATH I52
J 0
(-6150 5500);
DISPLAY 0.680851 (-6150 5500);
DISPLAY INVISIBLE (-6150 5500);
FORCEADD OFFPAGE..5
R 2
(-6350 5500);
FORCEPROP 2 LAST $XR0 343 
J 0
(-6161 5500);
DISPLAY 0.638298 (-6161 5500);
PAINT MONO (-6161 5500);
FORCEPROP 2 LAST CDS_LIB standard
J 0
(-6350 5500);
DISPLAY INVISIBLE (-6350 5500);
FORCEPROP 1 LAST OFFPAGE TRUE
J 2
(-6675 5375);
DISPLAY 0.872340 (-6675 5375);
PAINT GREEN (-6675 5375);
DISPLAY INVISIBLE (-6675 5375);
FORCEPROP 1 LAST COMMENT_BODY TRUE
J 2
(-6450 5425);
DISPLAY 0.872340 (-6450 5425);
PAINT GREEN (-6450 5425);
DISPLAY INVISIBLE (-6450 5425);
FORCEPROP 2 LAST PATH I53
J 0
(-6150 5550);
DISPLAY 0.680851 (-6150 5550);
DISPLAY INVISIBLE (-6150 5550);
FORCEADD OFFPAGE..5
R 2
(-6350 5675);
FORCEPROP 2 LAST $XR0 343 
J 0
(-6161 5675);
DISPLAY 0.638298 (-6161 5675);
PAINT MONO (-6161 5675);
FORCEPROP 2 LAST CDS_LIB standard
J 0
(-6350 5675);
DISPLAY INVISIBLE (-6350 5675);
FORCEPROP 1 LAST OFFPAGE TRUE
J 2
(-6675 5550);
DISPLAY 0.872340 (-6675 5550);
PAINT GREEN (-6675 5550);
DISPLAY INVISIBLE (-6675 5550);
FORCEPROP 1 LAST COMMENT_BODY TRUE
J 2
(-6450 5600);
DISPLAY 0.872340 (-6450 5600);
PAINT GREEN (-6450 5600);
DISPLAY INVISIBLE (-6450 5600);
FORCEPROP 2 LAST PATH I54
J 0
(-6150 5725);
DISPLAY 0.680851 (-6150 5725);
DISPLAY INVISIBLE (-6150 5725);
FORCEADD OFFPAGE..5
R 2
(-6350 5600);
FORCEPROP 2 LAST $XR0 343 
J 0
(-6161 5600);
DISPLAY 0.638298 (-6161 5600);
PAINT MONO (-6161 5600);
FORCEPROP 2 LAST CDS_LIB standard
J 0
(-6350 5600);
DISPLAY INVISIBLE (-6350 5600);
FORCEPROP 1 LAST OFFPAGE TRUE
J 2
(-6675 5475);
DISPLAY 0.872340 (-6675 5475);
PAINT GREEN (-6675 5475);
DISPLAY INVISIBLE (-6675 5475);
FORCEPROP 1 LAST COMMENT_BODY TRUE
J 2
(-6450 5525);
DISPLAY 0.872340 (-6450 5525);
PAINT GREEN (-6450 5525);
DISPLAY INVISIBLE (-6450 5525);
FORCEPROP 2 LAST PATH I55
J 0
(-6150 5650);
DISPLAY 0.680851 (-6150 5650);
DISPLAY INVISIBLE (-6150 5650);
FORCEADD OFFPAGE..5
R 2
(-6350 5550);
FORCEPROP 2 LAST $XR0 343 
J 0
(-6161 5550);
DISPLAY 0.638298 (-6161 5550);
PAINT MONO (-6161 5550);
FORCEPROP 2 LAST CDS_LIB standard
J 0
(-6350 5550);
DISPLAY INVISIBLE (-6350 5550);
FORCEPROP 1 LAST OFFPAGE TRUE
J 2
(-6675 5425);
DISPLAY 0.872340 (-6675 5425);
PAINT GREEN (-6675 5425);
DISPLAY INVISIBLE (-6675 5425);
FORCEPROP 1 LAST COMMENT_BODY TRUE
J 2
(-6450 5475);
DISPLAY 0.872340 (-6450 5475);
PAINT GREEN (-6450 5475);
DISPLAY INVISIBLE (-6450 5475);
FORCEPROP 2 LAST PATH I56
J 0
(-6150 5600);
DISPLAY 0.680851 (-6150 5600);
DISPLAY INVISIBLE (-6150 5600);
FORCEADD UNIVERSAL_GND..1
(-5000 5175);
FORCEPROP 3 LASTPIN (-5000 5225) SIG_NAME GND\g
J 0
(-4990 5235);
DISPLAY 0.659574 (-4990 5235);
PAINT MONO (-4990 5235);
DISPLAY INVISIBLE (-4990 5235);
FORCEPROP 2 LAST CDS_LIB pure_quanta_power
J 0
(-5000 5175);
DISPLAY INVISIBLE (-5000 5175);
FORCEPROP 1 LAST HDL_POWER GND
J 1
(-4975 5100);
DISPLAY 0.872340 (-4975 5100);
PAINT GREEN (-4975 5100);
DISPLAY INVISIBLE (-4975 5100);
FORCEPROP 1 LAST PATH I57
J 0
(-4925 5175);
DISPLAY 0.872340 (-4925 5175);
PAINT AQUA (-4925 5175);
DISPLAY INVISIBLE (-4925 5175);
FORCEADD Q_RES..2
(-5000 5525);
FORCEPROP 1 LAST LOCATION R886
J 0
(-4955 5650);
DISPLAY 0.787234 (-4955 5650);
FORCEPROP 0 LAST $SEC 1
J 0
(-4950 5700);
DISPLAY 0.680851 (-4950 5700);
PAINT MONO (-4950 5700);
DISPLAY INVISIBLE (-4950 5700);
FORCEPROP 0 LAST CDS_SEC 1
J 0
(-4950 5700);
DISPLAY 0.680851 (-4950 5700);
DISPLAY INVISIBLE (-4950 5700);
FORCEPROP 1 LASTPIN (-5000 5625) $PN 1
J 0
(-4995 5587);
DISPLAY 0.787234 (-4995 5587);
PAINT MONO (-4995 5587);
FORCEPROP 1 LASTPIN (-5000 5425) $PN 2
J 0
(-4995 5435);
DISPLAY 0.787234 (-4995 5435);
PAINT MONO (-4995 5435);
FORCEPROP 1 LAST VALUE 4.7K
J 0
(-4955 5600);
DISPLAY 0.787234 (-4955 5600);
FORCEPROP 1 LAST WATTAGE 1/20W
J 0
(-4960 5500);
DISPLAY 0.787234 (-4960 5500);
FORCEPROP 1 LAST PACK_TYPE 0201LF
J 0
(-4960 5350);
DISPLAY 0.787234 (-4960 5350);
FORCEPROP 1 LAST TOLERANCE 5%
J 0
(-4955 5550);
DISPLAY 0.787234 (-4955 5550);
FORCEPROP 1 LAST MATERIAL EMPTY
J 0
(-4960 5450);
DISPLAY 0.787234 (-4960 5450);
FORCEPROP 2 LAST CDS_LIB pure_quanta
J 0
(-5000 5525);
DISPLAY INVISIBLE (-5000 5525);
FORCEPROP 1 LAST PATH I58
J 0
(-4950 5700);
DISPLAY 0.978723 (-4950 5700);
PAINT WHITE (-4950 5700);
DISPLAY INVISIBLE (-4950 5700);
FORCEPROP 1 LAST PART_NUMBER CS24701JE04
J 0
(-4960 5400);
DISPLAY 0.787234 (-4960 5400);
DISPLAY INVISIBLE (-4960 5400);
FORCEADD Q_RES..2
(-5000 6050);
FORCEPROP 1 LAST LOCATION R885
J 0
(-4955 6175);
DISPLAY 0.787234 (-4955 6175);
FORCEPROP 0 LAST $SEC 1
J 0
(-4950 6225);
DISPLAY 0.680851 (-4950 6225);
PAINT MONO (-4950 6225);
DISPLAY INVISIBLE (-4950 6225);
FORCEPROP 0 LAST CDS_SEC 1
J 0
(-4950 6225);
DISPLAY 0.680851 (-4950 6225);
DISPLAY INVISIBLE (-4950 6225);
FORCEPROP 1 LASTPIN (-5000 6150) $PN 1
J 0
(-4995 6112);
DISPLAY 0.787234 (-4995 6112);
PAINT MONO (-4995 6112);
FORCEPROP 1 LASTPIN (-5000 5950) $PN 2
J 0
(-4995 5960);
DISPLAY 0.787234 (-4995 5960);
PAINT MONO (-4995 5960);
FORCEPROP 1 LAST PACK_TYPE 0201LF
J 0
(-4960 5875);
DISPLAY 0.787234 (-4960 5875);
FORCEPROP 1 LAST MATERIAL CHIP
J 0
(-4960 5975);
DISPLAY 0.787234 (-4960 5975);
FORCEPROP 1 LAST WATTAGE 1/20W
J 0
(-4960 6025);
DISPLAY 0.787234 (-4960 6025);
FORCEPROP 1 LAST TOLERANCE 5%
J 0
(-4955 6075);
DISPLAY 0.787234 (-4955 6075);
FORCEPROP 1 LAST VALUE 4.7K
J 0
(-4955 6125);
DISPLAY 0.787234 (-4955 6125);
FORCEPROP 2 LAST CDS_LIB pure_quanta
J 0
(-5000 6050);
DISPLAY INVISIBLE (-5000 6050);
FORCEPROP 1 LAST PATH I59
J 0
(-4950 6225);
DISPLAY 0.978723 (-4950 6225);
PAINT WHITE (-4950 6225);
DISPLAY INVISIBLE (-4950 6225);
FORCEPROP 1 LAST PART_NUMBER CS24701JE04
J 0
(-4960 5925);
DISPLAY 0.787234 (-4960 5925);
DISPLAY INVISIBLE (-4960 5925);
FORCEADD P1V0..1
(-5000 6375);
FORCEPROP 3 LASTPIN (-5000 6325) SIG_NAME P1V8_CPU1_RT_1D\g
J 0
(-4990 6335);
DISPLAY 0.659574 (-4990 6335);
PAINT MONO (-4990 6335);
DISPLAY INVISIBLE (-4990 6335);
FORCEPROP 1 LAST HDL_POWER P1V8_CPU1_RT_1D
J 1
(-5000 6425);
DISPLAY 0.489362 (-5000 6425);
PAINT SKYBLUE (-5000 6425);
FORCEPROP 2 LAST CDS_LIB pure_quanta_power
J 0
(-5000 6375);
DISPLAY INVISIBLE (-5000 6375);
FORCEPROP 1 LAST PATH I60
J 0
(-4950 6400);
DISPLAY 0.872340 (-4950 6400);
PAINT AQUA (-4950 6400);
DISPLAY INVISIBLE (-4950 6400);
FORCEADD UNIVERSAL_GND..1
R 1
(-3325 1675);
FORCEPROP 3 LASTPIN (-3375 1675) SIG_NAME GND\g
J 0
(-3365 1685);
DISPLAY 0.659574 (-3365 1685);
PAINT MONO (-3365 1685);
DISPLAY INVISIBLE (-3365 1685);
FORCEPROP 2 LAST CDS_LIB pure_quanta_power
J 0
(-3325 1675);
DISPLAY INVISIBLE (-3325 1675);
FORCEPROP 1 LAST HDL_POWER GND
R 1
J 1
(-3250 1700);
DISPLAY 0.872340 (-3250 1700);
PAINT GREEN (-3250 1700);
DISPLAY INVISIBLE (-3250 1700);
FORCEPROP 1 LAST PATH I61
R 1
J 0
(-3325 1750);
DISPLAY 0.872340 (-3325 1750);
PAINT AQUA (-3325 1750);
DISPLAY INVISIBLE (-3325 1750);
FORCEADD Q_RES..1
(-2550 2075);
FORCEPROP 1 LAST LOCATION R860
J 0
(-2825 2075);
DISPLAY 0.978723 (-2825 2075);
FORCEPROP 0 LAST $SEC 1
J 0
(-2250 2125);
DISPLAY 0.680851 (-2250 2125);
PAINT MONO (-2250 2125);
DISPLAY INVISIBLE (-2250 2125);
FORCEPROP 0 LAST CDS_SEC 1
J 0
(-2250 2125);
DISPLAY 0.680851 (-2250 2125);
DISPLAY INVISIBLE (-2250 2125);
FORCEPROP 1 LASTPIN (-2650 2075) $PN 1
J 0
(-2638 2087);
DISPLAY 0.787234 (-2638 2087);
PAINT MONO (-2638 2087);
FORCEPROP 1 LASTPIN (-2450 2075) $PN 2
J 0
(-2488 2087);
DISPLAY 0.787234 (-2488 2087);
PAINT MONO (-2488 2087);
FORCEPROP 1 LAST VALUE 0
J 2
(-2350 2075);
DISPLAY 0.787234 (-2350 2075);
FORCEPROP 1 LAST PACK_TYPE 0201LF
J 0
(-2250 2075);
DISPLAY 0.787234 (-2250 2075);
FORCEPROP 1 LAST WATTAGE 1/20W
J 2
(-2750 2150);
DISPLAY 0.787234 (-2750 2150);
DISPLAY INVISIBLE (-2750 2150);
FORCEPROP 1 LAST TOLERANCE 5%
J 0
(-2725 2200);
DISPLAY 0.787234 (-2725 2200);
DISPLAY INVISIBLE (-2725 2200);
FORCEPROP 1 LAST MATERIAL CHIP
J 0
(-2725 2150);
DISPLAY 0.787234 (-2725 2150);
DISPLAY INVISIBLE (-2725 2150);
FORCEPROP 2 LAST CDS_LIB pure_quanta
J 0
(-2550 2075);
DISPLAY INVISIBLE (-2550 2075);
FORCEPROP 1 LAST PATH I62
J 0
(-2600 2225);
DISPLAY 0.978723 (-2600 2225);
PAINT WHITE (-2600 2225);
DISPLAY INVISIBLE (-2600 2225);
FORCEPROP 1 LAST PART_NUMBER CS00001JE10
J 0
(-2600 2200);
DISPLAY 0.808511 (-2600 2200);
DISPLAY INVISIBLE (-2600 2200);
FORCEADD Q_RES..1
(-2550 2175);
FORCEPROP 1 LAST LOCATION R854
J 0
(-2825 2175);
DISPLAY 0.978723 (-2825 2175);
FORCEPROP 2 LAST SEC 1
J 0
(-2600 2375);
DISPLAY 0.680851 (-2600 2375);
PAINT MONO (-2600 2375);
DISPLAY INVISIBLE (-2600 2375);
FORCEPROP 1 LASTPIN (-2650 2175) $PN 1
J 0
(-2638 2187);
DISPLAY 0.787234 (-2638 2187);
PAINT MONO (-2638 2187);
FORCEPROP 1 LASTPIN (-2450 2175) $PN 2
J 0
(-2488 2187);
DISPLAY 0.787234 (-2488 2187);
PAINT MONO (-2488 2187);
FORCEPROP 1 LAST PACK_TYPE 0201LF
J 0
(-2250 2175);
DISPLAY 0.787234 (-2250 2175);
FORCEPROP 1 LAST VALUE 0
J 2
(-2350 2175);
DISPLAY 0.787234 (-2350 2175);
FORCEPROP 2 LAST CDS_LIB pure_quanta
J 0
(-2550 2175);
DISPLAY INVISIBLE (-2550 2175);
FORCEPROP 2 LAST SEC_TYPE 0201LF
J 0
(-2600 2375);
DISPLAY 0.680851 (-2600 2375);
DISPLAY INVISIBLE (-2600 2375);
FORCEPROP 1 LAST MATERIAL CHIP
J 0
(-2725 2250);
DISPLAY 0.787234 (-2725 2250);
DISPLAY INVISIBLE (-2725 2250);
FORCEPROP 1 LAST TOLERANCE 5%
J 0
(-2725 2300);
DISPLAY 0.787234 (-2725 2300);
DISPLAY INVISIBLE (-2725 2300);
FORCEPROP 1 LAST WATTAGE 1/20W
J 2
(-2750 2250);
DISPLAY 0.787234 (-2750 2250);
DISPLAY INVISIBLE (-2750 2250);
FORCEPROP 1 LAST PATH I63
J 0
(-2600 2325);
DISPLAY 0.978723 (-2600 2325);
PAINT WHITE (-2600 2325);
DISPLAY INVISIBLE (-2600 2325);
FORCEPROP 1 LAST PART_NUMBER CS00001JE10
J 0
(-2600 2300);
DISPLAY 0.808511 (-2600 2300);
DISPLAY INVISIBLE (-2600 2300);
FORCEADD OFFPAGE..1
R 2
(-2350 2575);
FORCEPROP 2 LAST $XR0 343 
J 0
(-2164 2575);
DISPLAY 0.638298 (-2164 2575);
PAINT MONO (-2164 2575);
FORCEPROP 2 LAST CDS_LIB standard
J 0
(-2350 2575);
DISPLAY INVISIBLE (-2350 2575);
FORCEPROP 1 LAST OFFPAGE TRUE
J 2
(-2675 2450);
DISPLAY 0.872340 (-2675 2450);
DISPLAY INVISIBLE (-2675 2450);
FORCEPROP 1 LAST COMMENT_BODY TRUE
J 2
(-2475 2475);
DISPLAY 0.872340 (-2475 2475);
PAINT GREEN (-2475 2475);
DISPLAY INVISIBLE (-2475 2475);
FORCEPROP 2 LAST PATH I65
J 0
(-2150 2625);
DISPLAY 0.680851 (-2150 2625);
DISPLAY INVISIBLE (-2150 2625);
FORCEADD OFFPAGE..1
R 2
(-2450 3075);
FORCEPROP 2 LAST $XR0 343 
J 0
(-2264 3075);
DISPLAY 0.638298 (-2264 3075);
PAINT MONO (-2264 3075);
FORCEPROP 2 LAST CDS_LIB standard
J 0
(-2450 3075);
DISPLAY INVISIBLE (-2450 3075);
FORCEPROP 1 LAST OFFPAGE TRUE
J 2
(-2775 2950);
DISPLAY 0.872340 (-2775 2950);
DISPLAY INVISIBLE (-2775 2950);
FORCEPROP 1 LAST COMMENT_BODY TRUE
J 2
(-2575 2975);
DISPLAY 0.872340 (-2575 2975);
PAINT GREEN (-2575 2975);
DISPLAY INVISIBLE (-2575 2975);
FORCEPROP 2 LAST PATH I66
J 0
(-2250 3125);
DISPLAY 0.680851 (-2250 3125);
DISPLAY INVISIBLE (-2250 3125);
FORCEADD OFFPAGE..1
R 2
(-2375 2775);
FORCEPROP 2 LAST $XR0 343 
J 0
(-2189 2775);
DISPLAY 0.638298 (-2189 2775);
PAINT MONO (-2189 2775);
FORCEPROP 2 LAST CDS_LIB standard
J 2
(-2375 2775);
DISPLAY INVISIBLE (-2375 2775);
FORCEPROP 1 LAST OFFPAGE TRUE
J 2
(-2700 2650);
DISPLAY 0.872340 (-2700 2650);
DISPLAY INVISIBLE (-2700 2650);
FORCEPROP 1 LAST COMMENT_BODY TRUE
J 2
(-2500 2675);
DISPLAY 0.872340 (-2500 2675);
PAINT GREEN (-2500 2675);
DISPLAY INVISIBLE (-2500 2675);
FORCEPROP 2 LAST PATH I67
J 0
(-2175 2825);
DISPLAY 0.680851 (-2175 2825);
DISPLAY INVISIBLE (-2175 2825);
FORCEADD OFFPAGE..1
R 2
(-1025 2075);
FORCEPROP 2 LAST $XR1 343 
J 0
(-749 2075);
DISPLAY 0.638298 (-749 2075);
PAINT MONO (-749 2075);
FORCEPROP 2 LAST $XR0 81 
J 0
(-839 2075);
DISPLAY 0.638298 (-839 2075);
PAINT MONO (-839 2075);
FORCEPROP 2 LAST CDS_LIB standard
J 0
(-1025 2075);
DISPLAY INVISIBLE (-1025 2075);
FORCEPROP 1 LAST OFFPAGE TRUE
J 2
(-1350 1950);
DISPLAY 0.872340 (-1350 1950);
DISPLAY INVISIBLE (-1350 1950);
FORCEPROP 1 LAST COMMENT_BODY TRUE
J 2
(-1150 1975);
DISPLAY 0.872340 (-1150 1975);
PAINT GREEN (-1150 1975);
DISPLAY INVISIBLE (-1150 1975);
FORCEPROP 2 LAST PATH I69
J 0
(-725 2125);
DISPLAY 0.680851 (-725 2125);
DISPLAY INVISIBLE (-725 2125);
FORCEADD OFFPAGE..1
R 2
(-1025 2175);
FORCEPROP 2 LAST $XR1 343 
J 0
(-749 2175);
DISPLAY 0.638298 (-749 2175);
PAINT MONO (-749 2175);
FORCEPROP 2 LAST $XR0 81 
J 0
(-839 2175);
DISPLAY 0.638298 (-839 2175);
PAINT MONO (-839 2175);
FORCEPROP 2 LAST CDS_LIB standard
J 0
(-1025 2175);
DISPLAY INVISIBLE (-1025 2175);
FORCEPROP 1 LAST OFFPAGE TRUE
J 2
(-1350 2050);
DISPLAY 0.872340 (-1350 2050);
DISPLAY INVISIBLE (-1350 2050);
FORCEPROP 1 LAST COMMENT_BODY TRUE
J 2
(-1150 2075);
DISPLAY 0.872340 (-1150 2075);
PAINT GREEN (-1150 2075);
DISPLAY INVISIBLE (-1150 2075);
FORCEPROP 2 LAST PATH I70
J 0
(-725 2225);
DISPLAY 0.680851 (-725 2225);
DISPLAY INVISIBLE (-725 2225);
FORCEADD Q_RES..2
(-3600 5300);
FORCEPROP 1 LAST LOCATION R863
J 0
(-3555 5425);
DISPLAY 0.787234 (-3555 5425);
FORCEPROP 0 LAST $SEC 1
J 0
(-3550 5475);
DISPLAY 0.680851 (-3550 5475);
PAINT MONO (-3550 5475);
DISPLAY INVISIBLE (-3550 5475);
FORCEPROP 0 LAST CDS_SEC 1
J 0
(-3550 5475);
DISPLAY 0.680851 (-3550 5475);
DISPLAY INVISIBLE (-3550 5475);
FORCEPROP 1 LASTPIN (-3600 5400) $PN 1
J 0
(-3595 5362);
DISPLAY 0.787234 (-3595 5362);
PAINT MONO (-3595 5362);
FORCEPROP 1 LASTPIN (-3600 5200) $PN 2
J 0
(-3595 5210);
DISPLAY 0.787234 (-3595 5210);
PAINT MONO (-3595 5210);
FORCEPROP 1 LAST MATERIAL EMPTY
J 0
(-3560 5225);
DISPLAY 0.787234 (-3560 5225);
FORCEPROP 1 LAST VALUE 1K
J 0
(-3555 5375);
DISPLAY 0.787234 (-3555 5375);
FORCEPROP 1 LAST TOLERANCE 1%
J 0
(-3555 5325);
DISPLAY 0.787234 (-3555 5325);
FORCEPROP 1 LAST WATTAGE 1/20W
J 0
(-3560 5275);
DISPLAY 0.787234 (-3560 5275);
FORCEPROP 1 LAST PACK_TYPE 0201LF
J 0
(-3560 5125);
DISPLAY 0.787234 (-3560 5125);
FORCEPROP 2 LAST CDS_LIB pure_quanta
J 0
(-3600 5300);
DISPLAY INVISIBLE (-3600 5300);
FORCEPROP 1 LAST PATH I71
J 0
(-3550 5475);
DISPLAY 0.978723 (-3550 5475);
PAINT WHITE (-3550 5475);
DISPLAY INVISIBLE (-3550 5475);
FORCEPROP 1 LAST PART_NUMBER CS21001FE07
J 0
(-3560 5175);
DISPLAY 0.978723 (-3560 5175);
DISPLAY INVISIBLE (-3560 5175);
FORCEADD Q_RES..2
(-3300 5300);
FORCEPROP 1 LAST LOCATION R865
J 0
(-3255 5425);
DISPLAY 0.787234 (-3255 5425);
FORCEPROP 0 LAST $SEC 1
J 0
(-3250 5475);
DISPLAY 0.680851 (-3250 5475);
PAINT MONO (-3250 5475);
DISPLAY INVISIBLE (-3250 5475);
FORCEPROP 0 LAST CDS_SEC 1
J 0
(-3250 5475);
DISPLAY 0.680851 (-3250 5475);
DISPLAY INVISIBLE (-3250 5475);
FORCEPROP 1 LASTPIN (-3300 5400) $PN 1
J 0
(-3295 5362);
DISPLAY 0.787234 (-3295 5362);
PAINT MONO (-3295 5362);
FORCEPROP 1 LASTPIN (-3300 5200) $PN 2
J 0
(-3295 5210);
DISPLAY 0.787234 (-3295 5210);
PAINT MONO (-3295 5210);
FORCEPROP 1 LAST PACK_TYPE 0201LF
J 0
(-3260 5125);
DISPLAY 0.787234 (-3260 5125);
FORCEPROP 1 LAST MATERIAL CHIP
J 0
(-3260 5225);
DISPLAY 0.787234 (-3260 5225);
FORCEPROP 1 LAST WATTAGE 1/20W
J 0
(-3260 5275);
DISPLAY 0.787234 (-3260 5275);
FORCEPROP 1 LAST TOLERANCE 1%
J 0
(-3255 5325);
DISPLAY 0.787234 (-3255 5325);
FORCEPROP 1 LAST VALUE 20K
J 0
(-3255 5375);
DISPLAY 0.787234 (-3255 5375);
FORCEPROP 2 LAST CDS_LIB pure_quanta
J 0
(-3300 5300);
DISPLAY INVISIBLE (-3300 5300);
FORCEPROP 1 LAST PATH I72
J 0
(-3250 5475);
DISPLAY 0.978723 (-3250 5475);
PAINT WHITE (-3250 5475);
DISPLAY INVISIBLE (-3250 5475);
FORCEPROP 1 LAST PART_NUMBER CS32001FE00
J 0
(-3260 5175);
DISPLAY 0.978723 (-3260 5175);
DISPLAY INVISIBLE (-3260 5175);
FORCEADD OFFPAGE..5
R 2
(-4125 5775);
FORCEPROP 2 LAST $XR0 343 
J 0
(-3936 5775);
DISPLAY 0.638298 (-3936 5775);
PAINT MONO (-3936 5775);
FORCEPROP 2 LAST CDS_LIB standard
J 0
(-4125 5775);
DISPLAY INVISIBLE (-4125 5775);
FORCEPROP 1 LAST OFFPAGE TRUE
J 2
(-4450 5650);
DISPLAY 0.872340 (-4450 5650);
PAINT GREEN (-4450 5650);
DISPLAY INVISIBLE (-4450 5650);
FORCEPROP 1 LAST COMMENT_BODY TRUE
J 2
(-4225 5700);
DISPLAY 0.872340 (-4225 5700);
PAINT GREEN (-4225 5700);
DISPLAY INVISIBLE (-4225 5700);
FORCEPROP 2 LAST PATH I73
J 0
(-3925 5825);
DISPLAY 0.680851 (-3925 5825);
DISPLAY INVISIBLE (-3925 5825);
FORCEADD Q_RES..2
(-3600 6075);
FORCEPROP 1 LAST LOCATION R861
J 0
(-3555 6200);
DISPLAY 0.787234 (-3555 6200);
FORCEPROP 0 LAST $SEC 1
J 0
(-3550 6250);
DISPLAY 0.680851 (-3550 6250);
PAINT MONO (-3550 6250);
DISPLAY INVISIBLE (-3550 6250);
FORCEPROP 0 LAST CDS_SEC 1
J 0
(-3550 6250);
DISPLAY 0.680851 (-3550 6250);
DISPLAY INVISIBLE (-3550 6250);
FORCEPROP 1 LASTPIN (-3600 6175) $PN 1
J 0
(-3595 6137);
DISPLAY 0.787234 (-3595 6137);
PAINT MONO (-3595 6137);
FORCEPROP 1 LASTPIN (-3600 5975) $PN 2
J 0
(-3595 5985);
DISPLAY 0.787234 (-3595 5985);
PAINT MONO (-3595 5985);
FORCEPROP 1 LAST VALUE 1K
J 0
(-3555 6150);
DISPLAY 0.787234 (-3555 6150);
FORCEPROP 1 LAST TOLERANCE 1%
J 0
(-3555 6100);
DISPLAY 0.787234 (-3555 6100);
FORCEPROP 1 LAST WATTAGE 1/20W
J 0
(-3560 6050);
DISPLAY 0.787234 (-3560 6050);
FORCEPROP 1 LAST PACK_TYPE 0201LF
J 0
(-3560 5900);
DISPLAY 0.787234 (-3560 5900);
FORCEPROP 1 LAST MATERIAL CHIP
J 0
(-3560 6000);
DISPLAY 0.787234 (-3560 6000);
FORCEPROP 2 LAST CDS_LIB pure_quanta
J 0
(-3600 6075);
DISPLAY INVISIBLE (-3600 6075);
FORCEPROP 1 LAST PATH I74
J 0
(-3550 6250);
DISPLAY 0.978723 (-3550 6250);
PAINT WHITE (-3550 6250);
DISPLAY INVISIBLE (-3550 6250);
FORCEPROP 1 LAST PART_NUMBER CS21001FE07
J 0
(-3560 5950);
DISPLAY 0.978723 (-3560 5950);
DISPLAY INVISIBLE (-3560 5950);
FORCEADD Q_RES..2
(-3300 6075);
FORCEPROP 1 LAST LOCATION R864
J 0
(-3255 6200);
DISPLAY 0.978723 (-3255 6200);
FORCEPROP 0 LAST $SEC 1
J 0
(-3250 6250);
DISPLAY 0.680851 (-3250 6250);
PAINT MONO (-3250 6250);
DISPLAY INVISIBLE (-3250 6250);
FORCEPROP 0 LAST CDS_SEC 1
J 0
(-3250 6250);
DISPLAY 0.680851 (-3250 6250);
DISPLAY INVISIBLE (-3250 6250);
FORCEPROP 1 LASTPIN (-3300 6175) $PN 1
J 0
(-3295 6137);
DISPLAY 0.787234 (-3295 6137);
PAINT MONO (-3295 6137);
FORCEPROP 1 LASTPIN (-3300 5975) $PN 2
J 0
(-3295 5985);
DISPLAY 0.787234 (-3295 5985);
PAINT MONO (-3295 5985);
FORCEPROP 1 LAST PACK_TYPE 0201LF
J 0
(-3260 5900);
DISPLAY 0.787234 (-3260 5900);
FORCEPROP 1 LAST TOLERANCE 1%
J 0
(-3255 6100);
DISPLAY 0.787234 (-3255 6100);
FORCEPROP 1 LAST VALUE 1K
J 0
(-3255 6150);
DISPLAY 0.787234 (-3255 6150);
FORCEPROP 1 LAST WATTAGE 1/20W
J 0
(-3260 6050);
DISPLAY 0.787234 (-3260 6050);
FORCEPROP 1 LAST MATERIAL EMPTY
J 0
(-3260 6000);
DISPLAY 0.787234 (-3260 6000);
FORCEPROP 2 LAST CDS_LIB pure_quanta
J 0
(-3300 6075);
DISPLAY INVISIBLE (-3300 6075);
FORCEPROP 1 LAST PATH I75
J 0
(-3250 6250);
DISPLAY 0.978723 (-3250 6250);
PAINT WHITE (-3250 6250);
DISPLAY INVISIBLE (-3250 6250);
FORCEPROP 1 LAST PART_NUMBER CS21001FE07
J 0
(-3260 5950);
DISPLAY 0.978723 (-3260 5950);
DISPLAY INVISIBLE (-3260 5950);
FORCEADD Q_RES..2
(-2950 5300);
FORCEPROP 1 LAST LOCATION R892
J 0
(-2905 5425);
DISPLAY 0.978723 (-2905 5425);
FORCEPROP 0 LAST $SEC 1
J 0
(-2900 5475);
DISPLAY 0.680851 (-2900 5475);
PAINT MONO (-2900 5475);
DISPLAY INVISIBLE (-2900 5475);
FORCEPROP 0 LAST CDS_SEC 1
J 0
(-2900 5475);
DISPLAY 0.680851 (-2900 5475);
DISPLAY INVISIBLE (-2900 5475);
FORCEPROP 1 LASTPIN (-2950 5400) $PN 1
J 0
(-2945 5362);
DISPLAY 0.787234 (-2945 5362);
PAINT MONO (-2945 5362);
FORCEPROP 1 LASTPIN (-2950 5200) $PN 2
J 0
(-2945 5210);
DISPLAY 0.787234 (-2945 5210);
PAINT MONO (-2945 5210);
FORCEPROP 1 LAST MATERIAL CHIP
J 0
(-2910 5225);
DISPLAY 0.787234 (-2910 5225);
FORCEPROP 1 LAST TOLERANCE 1%
J 0
(-2905 5325);
DISPLAY 0.787234 (-2905 5325);
FORCEPROP 1 LAST WATTAGE 1/20W
J 0
(-2910 5275);
DISPLAY 0.787234 (-2910 5275);
FORCEPROP 1 LAST PACK_TYPE 0201LF
J 0
(-2910 5125);
DISPLAY 0.787234 (-2910 5125);
FORCEPROP 1 LAST VALUE 1K
J 0
(-2905 5375);
DISPLAY 0.787234 (-2905 5375);
FORCEPROP 2 LAST CDS_LIB pure_quanta
J 0
(-2950 5300);
DISPLAY INVISIBLE (-2950 5300);
FORCEPROP 1 LAST PATH I76
J 0
(-2900 5475);
DISPLAY 0.978723 (-2900 5475);
PAINT WHITE (-2900 5475);
DISPLAY INVISIBLE (-2900 5475);
FORCEPROP 1 LAST PART_NUMBER CS21001FE07
J 0
(-2910 5175);
DISPLAY 0.978723 (-2910 5175);
DISPLAY INVISIBLE (-2910 5175);
FORCEADD Q_RES..2
(-2950 6050);
FORCEPROP 1 LAST LOCATION R887
J 0
(-2905 6175);
DISPLAY 0.978723 (-2905 6175);
FORCEPROP 0 LAST $SEC 1
J 0
(-2900 6225);
DISPLAY 0.680851 (-2900 6225);
PAINT MONO (-2900 6225);
DISPLAY INVISIBLE (-2900 6225);
FORCEPROP 0 LAST CDS_SEC 1
J 0
(-2900 6225);
DISPLAY 0.680851 (-2900 6225);
DISPLAY INVISIBLE (-2900 6225);
FORCEPROP 1 LASTPIN (-2950 6150) $PN 1
J 0
(-2945 6112);
DISPLAY 0.787234 (-2945 6112);
PAINT MONO (-2945 6112);
FORCEPROP 1 LASTPIN (-2950 5950) $PN 2
J 0
(-2945 5960);
DISPLAY 0.787234 (-2945 5960);
PAINT MONO (-2945 5960);
FORCEPROP 1 LAST MATERIAL EMPTY
J 0
(-2910 5975);
DISPLAY 0.787234 (-2910 5975);
FORCEPROP 1 LAST TOLERANCE 1%
J 0
(-2905 6075);
DISPLAY 0.787234 (-2905 6075);
FORCEPROP 1 LAST VALUE 1K
J 0
(-2905 6125);
DISPLAY 0.787234 (-2905 6125);
FORCEPROP 1 LAST WATTAGE 1/20W
J 0
(-2910 6025);
DISPLAY 0.787234 (-2910 6025);
FORCEPROP 1 LAST PACK_TYPE 0201LF
J 0
(-2910 5875);
DISPLAY 0.787234 (-2910 5875);
FORCEPROP 2 LAST CDS_LIB pure_quanta
J 0
(-2950 6050);
DISPLAY INVISIBLE (-2950 6050);
FORCEPROP 1 LAST PATH I77
J 0
(-2900 6225);
DISPLAY 0.978723 (-2900 6225);
PAINT WHITE (-2900 6225);
DISPLAY INVISIBLE (-2900 6225);
FORCEPROP 1 LAST PART_NUMBER CS21001FE07
J 0
(-2910 5925);
DISPLAY 0.978723 (-2910 5925);
DISPLAY INVISIBLE (-2910 5925);
FORCEADD P1V0..1
(-3600 6500);
FORCEPROP 3 LASTPIN (-3600 6450) SIG_NAME P1V8_CPU1_RT_1D\g
J 0
(-3590 6460);
DISPLAY 0.659574 (-3590 6460);
PAINT MONO (-3590 6460);
DISPLAY INVISIBLE (-3590 6460);
FORCEPROP 1 LAST HDL_POWER P1V8_CPU1_RT_1D
J 1
(-3600 6550);
DISPLAY 0.489362 (-3600 6550);
PAINT SKYBLUE (-3600 6550);
FORCEPROP 2 LAST CDS_LIB pure_quanta_power
J 0
(-3600 6500);
DISPLAY INVISIBLE (-3600 6500);
FORCEPROP 1 LAST PATH I78
J 0
(-3550 6525);
DISPLAY 0.872340 (-3550 6525);
PAINT AQUA (-3550 6525);
DISPLAY INVISIBLE (-3550 6525);
FORCEADD GND..1
(-1450 4825);
FORCEPROP 3 LASTPIN (-1450 4875) SIG_NAME GND\g
J 0
(-1440 4885);
DISPLAY 0.659574 (-1440 4885);
PAINT MONO (-1440 4885);
DISPLAY INVISIBLE (-1440 4885);
FORCEPROP 2 LAST BOM_COST MEM
J 0
(-1550 4900);
DISPLAY 0.808511 (-1550 4900);
DISPLAY INVISIBLE (-1550 4900);
FORCEPROP 1 LAST SIZE 1B
J 0
(-1375 4775);
DISPLAY 0.851064 (-1375 4775);
PAINT GREEN (-1375 4775);
DISPLAY INVISIBLE (-1375 4775);
FORCEPROP 2 LAST CDS_LIB pure_quanta_power
J 0
(-1450 4825);
DISPLAY INVISIBLE (-1450 4825);
FORCEPROP 1 LAST HDL_POWER GND
J 0
(-1450 4975);
DISPLAY 0.851064 (-1450 4975);
PAINT GREEN (-1450 4975);
DISPLAY INVISIBLE (-1450 4975);
FORCEPROP 1 LAST PATH I79
J 0
(-1375 4825);
DISPLAY 0.872340 (-1375 4825);
PAINT AQUA (-1375 4825);
DISPLAY INVISIBLE (-1375 4825);
FORCEADD Q_RES..2
R 2
(-1450 5200);
FORCEPROP 1 LAST LOCATION R867
J 2
(-1495 5325);
DISPLAY 0.638298 (-1495 5325);
FORCEPROP 0 LAST $SEC 1
J 0
(-1475 5375);
DISPLAY 0.680851 (-1475 5375);
PAINT MONO (-1475 5375);
DISPLAY INVISIBLE (-1475 5375);
FORCEPROP 0 LAST CDS_SEC 1
J 0
(-1475 5375);
DISPLAY 0.680851 (-1475 5375);
DISPLAY INVISIBLE (-1475 5375);
FORCEPROP 1 LASTPIN (-1450 5300) $PN 1
J 2
(-1455 5262);
DISPLAY 0.787234 (-1455 5262);
PAINT MONO (-1455 5262);
FORCEPROP 1 LASTPIN (-1450 5100) $PN 2
J 2
(-1455 5110);
DISPLAY 0.787234 (-1455 5110);
PAINT MONO (-1455 5110);
FORCEPROP 1 LAST TOLERANCE 1%
J 2
(-1495 5225);
DISPLAY 0.638298 (-1495 5225);
FORCEPROP 1 LAST WATTAGE 1/20W
J 2
(-1490 5175);
DISPLAY 0.638298 (-1490 5175);
FORCEPROP 1 LAST VALUE 10K
J 2
(-1495 5275);
DISPLAY 0.638298 (-1495 5275);
FORCEPROP 1 LAST PACK_TYPE 0201LF
J 2
(-1490 5025);
DISPLAY 0.638298 (-1490 5025);
FORCEPROP 1 LAST MATERIAL CHIP
J 2
(-1490 5125);
DISPLAY 0.638298 (-1490 5125);
FORCEPROP 2 LAST CDS_LIB pure_quanta
J 2
(-1450 5200);
DISPLAY INVISIBLE (-1450 5200);
FORCEPROP 1 LAST PATH I80
J 2
(-1500 5375);
DISPLAY 0.978723 (-1500 5375);
PAINT WHITE (-1500 5375);
DISPLAY INVISIBLE (-1500 5375);
FORCEPROP 1 LAST PART_NUMBER CS31001FE17
J 2
(-1490 5075);
DISPLAY 0.638298 (-1490 5075);
DISPLAY INVISIBLE (-1490 5075);
FORCEADD GND..1
(-1275 4850);
FORCEPROP 3 LASTPIN (-1275 4900) SIG_NAME GND\g
J 0
(-1265 4910);
DISPLAY 0.659574 (-1265 4910);
PAINT MONO (-1265 4910);
DISPLAY INVISIBLE (-1265 4910);
FORCEPROP 2 LAST CDS_LIB pure_quanta_power
J 0
(-1275 4850);
DISPLAY INVISIBLE (-1275 4850);
FORCEPROP 2 LAST BOM_COST MEM
J 0
(-1375 4925);
DISPLAY 0.808511 (-1375 4925);
DISPLAY INVISIBLE (-1375 4925);
FORCEPROP 1 LAST SIZE 1B
J 0
(-1200 4800);
DISPLAY 0.851064 (-1200 4800);
PAINT GREEN (-1200 4800);
DISPLAY INVISIBLE (-1200 4800);
FORCEPROP 1 LAST HDL_POWER GND
J 0
(-1275 5000);
DISPLAY 0.851064 (-1275 5000);
PAINT GREEN (-1275 5000);
DISPLAY INVISIBLE (-1275 5000);
FORCEPROP 1 LAST PATH I81
J 0
(-1200 4850);
DISPLAY 0.872340 (-1200 4850);
PAINT AQUA (-1200 4850);
DISPLAY INVISIBLE (-1200 4850);
FORCEADD Q_RES..2
(-1275 5200);
FORCEPROP 1 LAST LOCATION R866
J 0
(-1230 5325);
DISPLAY 0.638298 (-1230 5325);
FORCEPROP 0 LAST $SEC 1
J 0
(-1225 5375);
DISPLAY 0.680851 (-1225 5375);
PAINT MONO (-1225 5375);
DISPLAY INVISIBLE (-1225 5375);
FORCEPROP 0 LAST CDS_SEC 1
J 0
(-1225 5375);
DISPLAY 0.680851 (-1225 5375);
DISPLAY INVISIBLE (-1225 5375);
FORCEPROP 1 LASTPIN (-1275 5300) $PN 1
J 0
(-1270 5262);
DISPLAY 0.787234 (-1270 5262);
PAINT MONO (-1270 5262);
FORCEPROP 1 LASTPIN (-1275 5100) $PN 2
J 0
(-1270 5110);
DISPLAY 0.787234 (-1270 5110);
PAINT MONO (-1270 5110);
FORCEPROP 1 LAST PACK_TYPE 0201LF
J 0
(-1235 5025);
DISPLAY 0.638298 (-1235 5025);
FORCEPROP 1 LAST MATERIAL CHIP
J 0
(-1235 5125);
DISPLAY 0.638298 (-1235 5125);
FORCEPROP 1 LAST TOLERANCE 1%
J 0
(-1230 5225);
DISPLAY 0.638298 (-1230 5225);
FORCEPROP 1 LAST WATTAGE 1/20W
J 0
(-1235 5175);
DISPLAY 0.638298 (-1235 5175);
FORCEPROP 1 LAST VALUE 10K
J 0
(-1230 5275);
DISPLAY 0.638298 (-1230 5275);
FORCEPROP 2 LAST CDS_LIB pure_quanta
J 0
(-1275 5200);
DISPLAY INVISIBLE (-1275 5200);
FORCEPROP 1 LAST PATH I82
J 0
(-1225 5375);
DISPLAY 0.978723 (-1225 5375);
PAINT WHITE (-1225 5375);
DISPLAY INVISIBLE (-1225 5375);
FORCEPROP 1 LAST PART_NUMBER CS31001FE17
J 0
(-1235 5075);
DISPLAY 0.638298 (-1235 5075);
DISPLAY INVISIBLE (-1235 5075);
FORCEADD OFFPAGE..5
R 2
(-2050 5550);
FORCEPROP 2 LAST $XR0 343 
J 0
(-1861 5550);
DISPLAY 0.638298 (-1861 5550);
PAINT MONO (-1861 5550);
FORCEPROP 2 LAST CDS_LIB standard
J 0
(-2050 5550);
DISPLAY INVISIBLE (-2050 5550);
FORCEPROP 1 LAST OFFPAGE TRUE
J 2
(-2375 5425);
DISPLAY 0.872340 (-2375 5425);
PAINT GREEN (-2375 5425);
DISPLAY INVISIBLE (-2375 5425);
FORCEPROP 1 LAST COMMENT_BODY TRUE
J 2
(-2150 5475);
DISPLAY 0.872340 (-2150 5475);
PAINT GREEN (-2150 5475);
DISPLAY INVISIBLE (-2150 5475);
FORCEPROP 2 LAST PATH I83
J 0
(-1850 5600);
DISPLAY 0.680851 (-1850 5600);
DISPLAY INVISIBLE (-1850 5600);
FORCEADD OFFPAGE..5
R 2
(-2050 5650);
FORCEPROP 2 LAST $XR0 343 
J 0
(-1861 5650);
DISPLAY 0.638298 (-1861 5650);
PAINT MONO (-1861 5650);
FORCEPROP 2 LAST CDS_LIB standard
J 0
(-2050 5650);
DISPLAY INVISIBLE (-2050 5650);
FORCEPROP 1 LAST OFFPAGE TRUE
J 2
(-2375 5525);
DISPLAY 0.872340 (-2375 5525);
PAINT GREEN (-2375 5525);
DISPLAY INVISIBLE (-2375 5525);
FORCEPROP 1 LAST COMMENT_BODY TRUE
J 2
(-2150 5575);
DISPLAY 0.872340 (-2150 5575);
PAINT GREEN (-2150 5575);
DISPLAY INVISIBLE (-2150 5575);
FORCEPROP 2 LAST PATH I84
J 0
(-1850 5700);
DISPLAY 0.680851 (-1850 5700);
DISPLAY INVISIBLE (-1850 5700);
FORCEADD OFFPAGE..5
R 2
(-2050 5750);
FORCEPROP 2 LAST $XR0 343 
J 0
(-1861 5750);
DISPLAY 0.638298 (-1861 5750);
PAINT MONO (-1861 5750);
FORCEPROP 2 LAST CDS_LIB standard
J 0
(-2050 5750);
DISPLAY INVISIBLE (-2050 5750);
FORCEPROP 1 LAST OFFPAGE TRUE
J 2
(-2375 5625);
DISPLAY 0.872340 (-2375 5625);
PAINT GREEN (-2375 5625);
DISPLAY INVISIBLE (-2375 5625);
FORCEPROP 1 LAST COMMENT_BODY TRUE
J 2
(-2150 5675);
DISPLAY 0.872340 (-2150 5675);
PAINT GREEN (-2150 5675);
DISPLAY INVISIBLE (-2150 5675);
FORCEPROP 2 LAST PATH I85
J 0
(-1850 5800);
DISPLAY 0.680851 (-1850 5800);
DISPLAY INVISIBLE (-1850 5800);
FORCEADD Q_RES..2
R 2
(-1450 6025);
FORCEPROP 1 LAST LOCATION R870
J 2
(-1495 6150);
DISPLAY 0.787234 (-1495 6150);
FORCEPROP 0 LAST $SEC 1
J 0
(-1475 6200);
DISPLAY 0.680851 (-1475 6200);
PAINT MONO (-1475 6200);
DISPLAY INVISIBLE (-1475 6200);
FORCEPROP 0 LAST CDS_SEC 1
J 0
(-1475 6200);
DISPLAY 0.680851 (-1475 6200);
DISPLAY INVISIBLE (-1475 6200);
FORCEPROP 1 LASTPIN (-1450 6125) $PN 1
J 2
(-1455 6087);
DISPLAY 0.787234 (-1455 6087);
PAINT MONO (-1455 6087);
FORCEPROP 1 LASTPIN (-1450 5925) $PN 2
J 2
(-1455 5935);
DISPLAY 0.787234 (-1455 5935);
PAINT MONO (-1455 5935);
FORCEPROP 1 LAST TOLERANCE 5%
J 2
(-1495 6050);
DISPLAY 0.787234 (-1495 6050);
FORCEPROP 1 LAST WATTAGE 1/20W
J 2
(-1490 6000);
DISPLAY 0.787234 (-1490 6000);
FORCEPROP 1 LAST VALUE 4.7K
J 2
(-1495 6100);
DISPLAY 0.787234 (-1495 6100);
FORCEPROP 1 LAST MATERIAL EMPTY
J 2
(-1490 5950);
DISPLAY 0.787234 (-1490 5950);
FORCEPROP 1 LAST PACK_TYPE 0201LF
J 2
(-1500 5875);
DISPLAY 0.787234 (-1500 5875);
FORCEPROP 2 LAST CDS_LIB pure_quanta
J 2
(-1450 6025);
DISPLAY INVISIBLE (-1450 6025);
FORCEPROP 1 LAST PATH I86
J 2
(-1500 6200);
DISPLAY 0.978723 (-1500 6200);
PAINT WHITE (-1500 6200);
DISPLAY INVISIBLE (-1500 6200);
FORCEPROP 1 LAST PART_NUMBER CS24701JE04
J 2
(-1490 5900);
DISPLAY 0.978723 (-1490 5900);
DISPLAY INVISIBLE (-1490 5900);
FORCEADD P1V0..1
(-1450 6275);
FORCEPROP 3 LASTPIN (-1450 6225) SIG_NAME P1V8_CPU1_RT_1D\g
J 0
(-1440 6235);
DISPLAY 0.659574 (-1440 6235);
PAINT MONO (-1440 6235);
DISPLAY INVISIBLE (-1440 6235);
FORCEPROP 1 LAST HDL_POWER P1V8_CPU1_RT_1D
J 1
(-1450 6325);
DISPLAY 0.489362 (-1450 6325);
PAINT SKYBLUE (-1450 6325);
FORCEPROP 2 LAST CDS_LIB pure_quanta_power
J 0
(-1450 6275);
DISPLAY INVISIBLE (-1450 6275);
FORCEPROP 1 LAST PATH I87
J 0
(-1400 6300);
DISPLAY 0.872340 (-1400 6300);
PAINT AQUA (-1400 6300);
DISPLAY INVISIBLE (-1400 6300);
FORCEADD OFFPAGE..1
R 2
(-500 5425);
FORCEPROP 2 LAST $XR1 343 
J 0
(-224 5425);
DISPLAY 0.638298 (-224 5425);
PAINT MONO (-224 5425);
FORCEPROP 2 LAST $XR0 81 
J 0
(-314 5425);
DISPLAY 0.638298 (-314 5425);
PAINT MONO (-314 5425);
FORCEPROP 2 LAST CDS_LIB standard
J 0
(-500 5425);
DISPLAY INVISIBLE (-500 5425);
FORCEPROP 1 LAST OFFPAGE TRUE
J 2
(-825 5300);
DISPLAY 0.872340 (-825 5300);
PAINT GREEN (-825 5300);
DISPLAY INVISIBLE (-825 5300);
FORCEPROP 1 LAST COMMENT_BODY TRUE
J 2
(-625 5325);
DISPLAY 0.872340 (-625 5325);
PAINT GREEN (-625 5325);
DISPLAY INVISIBLE (-625 5325);
FORCEPROP 2 LAST PATH I88
J 0
(-200 5475);
DISPLAY 0.680851 (-200 5475);
DISPLAY INVISIBLE (-200 5475);
FORCEADD OFFPAGE..1
R 2
(-475 5575);
FORCEPROP 2 LAST $XR1 343 
J 0
(-199 5575);
DISPLAY 0.638298 (-199 5575);
PAINT MONO (-199 5575);
FORCEPROP 2 LAST $XR0 81 
J 0
(-289 5575);
DISPLAY 0.638298 (-289 5575);
PAINT MONO (-289 5575);
FORCEPROP 2 LAST CDS_LIB standard
J 0
(-475 5575);
DISPLAY INVISIBLE (-475 5575);
FORCEPROP 1 LAST OFFPAGE TRUE
J 2
(-800 5450);
DISPLAY 0.872340 (-800 5450);
PAINT GREEN (-800 5450);
DISPLAY INVISIBLE (-800 5450);
FORCEPROP 1 LAST COMMENT_BODY TRUE
J 2
(-600 5475);
DISPLAY 0.872340 (-600 5475);
PAINT GREEN (-600 5475);
DISPLAY INVISIBLE (-600 5475);
FORCEPROP 2 LAST PATH I89
J 0
(-275 5625);
DISPLAY 0.680851 (-275 5625);
DISPLAY INVISIBLE (-275 5625);
FORCEADD UNIVERSAL_GND..1
(-6125 375);
FORCEPROP 3 LASTPIN (-6125 425) SIG_NAME GND\g
J 0
(-6115 435);
DISPLAY 0.659574 (-6115 435);
PAINT MONO (-6115 435);
DISPLAY INVISIBLE (-6115 435);
FORCEPROP 2 LAST CDS_LIB pure_quanta_power
J 0
(-6125 375);
DISPLAY INVISIBLE (-6125 375);
FORCEPROP 1 LAST HDL_POWER GND
J 1
(-6100 300);
DISPLAY 0.872340 (-6100 300);
PAINT GREEN (-6100 300);
DISPLAY INVISIBLE (-6100 300);
FORCEPROP 1 LAST PATH I90
J 0
(-6050 375);
DISPLAY 0.872340 (-6050 375);
PAINT AQUA (-6050 375);
DISPLAY INVISIBLE (-6050 375);
FORCEADD UNIVERSAL_GND..1
(-6275 375);
FORCEPROP 3 LASTPIN (-6275 425) SIG_NAME GND\g
J 0
(-6265 435);
DISPLAY 0.659574 (-6265 435);
PAINT MONO (-6265 435);
DISPLAY INVISIBLE (-6265 435);
FORCEPROP 2 LAST CDS_LIB pure_quanta_power
J 0
(-6275 375);
DISPLAY INVISIBLE (-6275 375);
FORCEPROP 1 LAST HDL_POWER GND
J 1
(-6250 300);
DISPLAY 0.872340 (-6250 300);
PAINT GREEN (-6250 300);
DISPLAY INVISIBLE (-6250 300);
FORCEPROP 1 LAST PATH I91
J 0
(-6200 375);
DISPLAY 0.872340 (-6200 375);
PAINT AQUA (-6200 375);
DISPLAY INVISIBLE (-6200 375);
FORCEADD Q_RES..2
R 2
(-6275 700);
FORCEPROP 1 LAST LOCATION R637
J 2
(-6320 825);
DISPLAY 0.978723 (-6320 825);
FORCEPROP 0 LAST $SEC 1
J 0
(-6300 875);
DISPLAY 0.680851 (-6300 875);
PAINT MONO (-6300 875);
DISPLAY INVISIBLE (-6300 875);
FORCEPROP 0 LAST CDS_SEC 1
J 0
(-6300 875);
DISPLAY 0.680851 (-6300 875);
DISPLAY INVISIBLE (-6300 875);
FORCEPROP 1 LASTPIN (-6275 800) $PN 1
J 2
(-6280 762);
DISPLAY 0.787234 (-6280 762);
PAINT MONO (-6280 762);
FORCEPROP 1 LASTPIN (-6275 600) $PN 2
J 2
(-6280 610);
DISPLAY 0.787234 (-6280 610);
PAINT MONO (-6280 610);
FORCEPROP 1 LAST WATTAGE 1/20W
J 2
(-6315 675);
DISPLAY 0.978723 (-6315 675);
FORCEPROP 1 LAST VALUE 51.1
J 2
(-6320 775);
DISPLAY 0.978723 (-6320 775);
FORCEPROP 1 LAST PACK_TYPE 0201LF
J 2
(-6315 525);
DISPLAY 0.978723 (-6315 525);
FORCEPROP 1 LAST TOLERANCE 1%
J 2
(-6320 725);
DISPLAY 0.978723 (-6320 725);
FORCEPROP 1 LAST MATERIAL EMPTY
J 2
(-6315 625);
DISPLAY 0.978723 (-6315 625);
FORCEPROP 2 LAST CDS_LIB pure_quanta
J 0
(-6275 700);
DISPLAY INVISIBLE (-6275 700);
FORCEPROP 1 LAST PATH I92
J 2
(-6325 875);
DISPLAY 0.978723 (-6325 875);
PAINT WHITE (-6325 875);
DISPLAY INVISIBLE (-6325 875);
FORCEPROP 1 LAST PART_NUMBER CS05111FE00
J 2
(-6315 575);
DISPLAY 0.978723 (-6315 575);
DISPLAY INVISIBLE (-6315 575);
FORCEADD OFFPAGE..1
(-6125 1925);
FORCEPROP 2 LAST $XR0 343 
J 0
(-6407 1925);
DISPLAY 0.638298 (-6407 1925);
PAINT MONO (-6407 1925);
FORCEPROP 2 LAST CDS_LIB standard
J 0
(-6125 1925);
DISPLAY INVISIBLE (-6125 1925);
FORCEPROP 1 LAST OFFPAGE TRUE
J 0
(-5800 1800);
DISPLAY 0.872340 (-5800 1800);
DISPLAY INVISIBLE (-5800 1800);
FORCEPROP 1 LAST COMMENT_BODY TRUE
J 0
(-6000 1825);
DISPLAY 0.872340 (-6000 1825);
PAINT GREEN (-6000 1825);
DISPLAY INVISIBLE (-6000 1825);
FORCEPROP 2 LAST PATH I93
J 0
(-6400 1975);
DISPLAY 0.680851 (-6400 1975);
DISPLAY INVISIBLE (-6400 1975);
FORCEADD OFFPAGE..1
(-6125 2025);
FORCEPROP 2 LAST $XR0 343 
J 0
(-6407 2025);
DISPLAY 0.638298 (-6407 2025);
PAINT MONO (-6407 2025);
FORCEPROP 2 LAST CDS_LIB standard
J 0
(-6125 2025);
DISPLAY INVISIBLE (-6125 2025);
FORCEPROP 1 LAST OFFPAGE TRUE
J 0
(-5800 1900);
DISPLAY 0.872340 (-5800 1900);
DISPLAY INVISIBLE (-5800 1900);
FORCEPROP 1 LAST COMMENT_BODY TRUE
J 0
(-6000 1925);
DISPLAY 0.872340 (-6000 1925);
PAINT GREEN (-6000 1925);
DISPLAY INVISIBLE (-6000 1925);
FORCEPROP 2 LAST PATH I94
J 0
(-6400 2075);
DISPLAY 0.680851 (-6400 2075);
DISPLAY INVISIBLE (-6400 2075);
FORCEADD OFFPAGE..1
(-6125 2125);
FORCEPROP 2 LAST $XR0 343 
J 0
(-6407 2125);
DISPLAY 0.638298 (-6407 2125);
PAINT MONO (-6407 2125);
FORCEPROP 2 LAST CDS_LIB standard
J 0
(-6125 2125);
DISPLAY INVISIBLE (-6125 2125);
FORCEPROP 1 LAST OFFPAGE TRUE
J 0
(-5800 2000);
DISPLAY 0.872340 (-5800 2000);
DISPLAY INVISIBLE (-5800 2000);
FORCEPROP 1 LAST COMMENT_BODY TRUE
J 0
(-6000 2025);
DISPLAY 0.872340 (-6000 2025);
PAINT GREEN (-6000 2025);
DISPLAY INVISIBLE (-6000 2025);
FORCEPROP 2 LAST PATH I95
J 0
(-6400 2175);
DISPLAY 0.680851 (-6400 2175);
DISPLAY INVISIBLE (-6400 2175);
FORCEADD UNIVERSAL_GND..1
(-3600 4875);
FORCEPROP 3 LASTPIN (-3600 4925) SIG_NAME GND\g
J 0
(-3590 4935);
DISPLAY 0.659574 (-3590 4935);
PAINT MONO (-3590 4935);
DISPLAY INVISIBLE (-3590 4935);
FORCEPROP 2 LAST CDS_LIB pure_quanta_power
J 0
(-3600 4875);
DISPLAY INVISIBLE (-3600 4875);
FORCEPROP 1 LAST HDL_POWER GND
J 1
(-3575 4800);
DISPLAY 0.872340 (-3575 4800);
PAINT GREEN (-3575 4800);
DISPLAY INVISIBLE (-3575 4800);
FORCEPROP 1 LAST PATH I96
J 0
(-3525 4875);
DISPLAY 0.872340 (-3525 4875);
PAINT AQUA (-3525 4875);
DISPLAY INVISIBLE (-3525 4875);
FORCEADD PT5161LRS..3
(-4350 2325);
FORCEPROP 1 LAST LOCATION U6016
J 0
(-4850 3950);
DISPLAY 0.723404 (-4850 3950);
PAINT GREEN (-4850 3950);
FORCEPROP 0 LAST $SEC 3
J 0
(-4850 4100);
DISPLAY 0.680851 (-4850 4100);
PAINT MONO (-4850 4100);
DISPLAY INVISIBLE (-4850 4100);
FORCEPROP 0 LAST CDS_SEC 3
J 0
(-4850 4100);
DISPLAY 0.680851 (-4850 4100);
DISPLAY INVISIBLE (-4850 4100);
FORCEPROP 0 LASTPIN (-3750 2275) $PN G35
J 0
(-3740 2285);
DISPLAY 0.680851 (-3740 2285);
PAINT MONO (-3740 2285);
FORCEPROP 0 LASTPIN (-5000 1625) $PN FF5
J 2
(-5010 1635);
DISPLAY 0.680851 (-5010 1635);
PAINT MONO (-5010 1635);
FORCEPROP 0 LASTPIN (-5000 1525) $PN FJ3
J 2
(-5010 1535);
DISPLAY 0.680851 (-5010 1535);
PAINT MONO (-5010 1535);
FORCEPROP 0 LASTPIN (-5000 3525) $PN FJ6
J 2
(-5010 3535);
DISPLAY 0.680851 (-5010 3535);
PAINT MONO (-5010 3535);
FORCEPROP 0 LASTPIN (-5000 3425) $PN FJ23
J 2
(-5010 3435);
DISPLAY 0.680851 (-5010 3435);
PAINT MONO (-5010 3435);
FORCEPROP 0 LASTPIN (-5000 3325) $PN FJ25
J 2
(-5010 3335);
DISPLAY 0.680851 (-5010 3335);
PAINT MONO (-5010 3335);
FORCEPROP 0 LASTPIN (-5000 3225) $PN FJ28
J 2
(-5010 3235);
DISPLAY 0.680851 (-5010 3235);
PAINT MONO (-5010 3235);
FORCEPROP 0 LASTPIN (-3750 1875) $PN FJ31
J 0
(-3740 1885);
DISPLAY 0.680851 (-3740 1885);
PAINT MONO (-3740 1885);
FORCEPROP 0 LASTPIN (-3750 3625) $PN B3
J 0
(-3740 3635);
DISPLAY 0.680851 (-3740 3635);
PAINT MONO (-3740 3635);
FORCEPROP 0 LASTPIN (-3750 3325) $PN B6
J 0
(-3740 3335);
DISPLAY 0.680851 (-3740 3335);
PAINT MONO (-3740 3335);
FORCEPROP 0 LASTPIN (-3750 3525) $PN B9
J 0
(-3740 3535);
DISPLAY 0.680851 (-3740 3535);
PAINT MONO (-3740 3535);
FORCEPROP 0 LASTPIN (-3750 3075) $PN FF8
J 0
(-3740 3085);
DISPLAY 0.680851 (-3740 3085);
PAINT MONO (-3740 3085);
FORCEPROP 0 LASTPIN (-3750 3425) $PN B12
J 0
(-3740 3435);
DISPLAY 0.680851 (-3740 3435);
PAINT MONO (-3740 3435);
FORCEPROP 0 LASTPIN (-3750 3225) $PN E8
J 0
(-3740 3235);
DISPLAY 0.680851 (-3740 3235);
PAINT MONO (-3740 3235);
FORCEPROP 0 LASTPIN (-3750 2775) $PN FJ9
J 0
(-3740 2785);
DISPLAY 0.680851 (-3740 2785);
PAINT MONO (-3740 2785);
FORCEPROP 0 LASTPIN (-3750 2175) $PN F2
J 0
(-3740 2185);
DISPLAY 0.680851 (-3740 2185);
PAINT MONO (-3740 2185);
FORCEPROP 0 LASTPIN (-3750 1025) $PN E18
J 0
(-3740 1035);
DISPLAY 0.680851 (-3740 1035);
PAINT MONO (-3740 1035);
FORCEPROP 0 LASTPIN (-3750 1175) $PN B16
J 0
(-3740 1185);
DISPLAY 0.680851 (-3740 1185);
PAINT MONO (-3740 1185);
FORCEPROP 0 LASTPIN (-5000 1025) $PN FF18
J 2
(-5010 1035);
DISPLAY 0.680851 (-5010 1035);
PAINT MONO (-5010 1035);
FORCEPROP 0 LASTPIN (-5000 1175) $PN FJ16
J 2
(-5010 1185);
DISPLAY 0.680851 (-5010 1185);
PAINT MONO (-5010 1185);
FORCEPROP 0 LASTPIN (-3750 2075) $PN FF11
J 0
(-3740 2085);
DISPLAY 0.680851 (-3740 2085);
PAINT MONO (-3740 2085);
FORCEPROP 0 LASTPIN (-3750 2675) $PN E11
J 0
(-3740 2685);
DISPLAY 0.680851 (-3740 2685);
PAINT MONO (-3740 2685);
FORCEPROP 0 LASTPIN (-3750 2575) $PN FF33
J 0
(-3740 2585);
DISPLAY 0.680851 (-3740 2585);
PAINT MONO (-3740 2585);
FORCEPROP 0 LASTPIN (-5000 2625) $PN F34
J 2
(-5010 2635);
DISPLAY 0.680851 (-5010 2635);
PAINT MONO (-5010 2635);
FORCEPROP 0 LASTPIN (-5000 2525) $PN B23
J 2
(-5010 2535);
DISPLAY 0.680851 (-5010 2535);
PAINT MONO (-5010 2535);
FORCEPROP 0 LASTPIN (-5000 2425) $PN B25
J 2
(-5010 2435);
DISPLAY 0.680851 (-5010 2435);
PAINT MONO (-5010 2435);
FORCEPROP 0 LASTPIN (-5000 2875) $PN B31
J 2
(-5010 2885);
DISPLAY 0.680851 (-5010 2885);
PAINT MONO (-5010 2885);
FORCEPROP 0 LASTPIN (-5000 2775) $PN B28
J 2
(-5010 2785);
DISPLAY 0.680851 (-5010 2785);
PAINT MONO (-5010 2785);
FORCEPROP 0 LASTPIN (-3750 1675) $PN E30
J 0
(-3740 1685);
DISPLAY 0.680851 (-3740 1685);
PAINT MONO (-3740 1685);
FORCEPROP 0 LASTPIN (-5000 2125) $PN FF24
J 2
(-5010 2135);
DISPLAY 0.680851 (-5010 2135);
PAINT MONO (-5010 2135);
FORCEPROP 0 LASTPIN (-5000 2025) $PN FF27
J 2
(-5010 2035);
DISPLAY 0.680851 (-5010 2035);
PAINT MONO (-5010 2035);
FORCEPROP 0 LASTPIN (-5000 1925) $PN FF30
J 2
(-5010 1935);
DISPLAY 0.680851 (-5010 1935);
PAINT MONO (-5010 1935);
FORCEPROP 2 LAST PART_TYPE SMLF
J 0
(-4850 4050);
DISPLAY 0.680851 (-4850 4050);
FORCEPROP 2 LAST VALUE PT5161LRS
J 0
(-4850 4000);
DISPLAY 0.680851 (-4850 4000);
FORCEPROP 1 LAST MATERIAL IC
J 0
(-4850 3800);
DISPLAY 0.723404 (-4850 3800);
PAINT GREEN (-4850 3800);
FORCEPROP 1 LAST NEEDS_NO_SIZE TRUE
J 0
(-4350 2325);
DISPLAY 0.723404 (-4350 2325);
PAINT GREEN (-4350 2325);
DISPLAY INVISIBLE (-4350 2325);
FORCEPROP 1 LAST CDS_LMAN_SYM_OUTLINE -500,1450,450,-1400
J 0
(-4350 2325);
DISPLAY 0.468085 (-4350 2325);
PAINT GREEN (-4350 2325);
DISPLAY INVISIBLE (-4350 2325);
FORCEPROP 2 LAST CDS_LIB pure_quanta
J 0
(-4350 2325);
DISPLAY INVISIBLE (-4350 2325);
FORCEPROP 1 LAST PATH I97
J 0
(-4350 2325);
DISPLAY 0.723404 (-4350 2325);
PAINT GREEN (-4350 2325);
DISPLAY INVISIBLE (-4350 2325);
FORCEPROP 1 LAST PART_NUMBER AJ051610U03
J 0
(-4850 3875);
DISPLAY 0.723404 (-4850 3875);
PAINT GREEN (-4850 3875);
DISPLAY INVISIBLE (-4850 3875);
FORCEADD Q_RES..1
(-2650 2275);
FORCEPROP 1 LAST LOCATION R1421
J 0
(-2700 2325);
DISPLAY 0.978723 (-2700 2325);
FORCEPROP 0 LAST $SEC 1
J 0
(-2700 2375);
DISPLAY 0.680851 (-2700 2375);
PAINT MONO (-2700 2375);
DISPLAY INVISIBLE (-2700 2375);
FORCEPROP 0 LAST CDS_SEC 1
J 0
(-2700 2375);
DISPLAY 0.680851 (-2700 2375);
DISPLAY INVISIBLE (-2700 2375);
FORCEPROP 1 LASTPIN (-2750 2275) $PN 1
J 0
(-2738 2287);
DISPLAY 0.787234 (-2738 2287);
PAINT MONO (-2738 2287);
FORCEPROP 1 LASTPIN (-2550 2275) $PN 2
J 0
(-2588 2287);
DISPLAY 0.787234 (-2588 2287);
PAINT MONO (-2588 2287);
FORCEPROP 1 LAST VALUE 4.7K
J 2
(-2400 2275);
DISPLAY 0.638298 (-2400 2275);
FORCEPROP 1 LAST PACK_TYPE 0201LF
J 0
(-2225 2275);
DISPLAY 0.638298 (-2225 2275);
FORCEPROP 1 LAST MATERIAL CHIP
J 0
(-2375 2275);
DISPLAY 0.638298 (-2375 2275);
FORCEPROP 2 LAST CDS_LIB pure_quanta
J 0
(-2650 2275);
DISPLAY INVISIBLE (-2650 2275);
FORCEPROP 1 LAST TOLERANCE 5%
J 0
(-2650 2175);
DISPLAY 0.978723 (-2650 2175);
DISPLAY INVISIBLE (-2650 2175);
FORCEPROP 1 LAST WATTAGE 1/20W
J 2
(-2675 2125);
DISPLAY 0.978723 (-2675 2125);
DISPLAY INVISIBLE (-2675 2125);
FORCEPROP 1 LAST PATH I98
J 0
(-2700 2425);
DISPLAY 0.978723 (-2700 2425);
PAINT WHITE (-2700 2425);
DISPLAY INVISIBLE (-2700 2425);
FORCEPROP 1 LAST PART_NUMBER CS24701JE04
J 0
(-2700 2375);
DISPLAY 0.978723 (-2700 2375);
DISPLAY INVISIBLE (-2700 2375);
FORCEADD DNS..1
(-1425 3825);
PAINT RED (-1425 3825);
FORCEPROP 2 LAST CDS_LIB mstr_misc
J 0
(-1425 3825);
DISPLAY INVISIBLE (-1425 3825);
FORCEPROP 1 LAST COMMENT_BODY TRUE
R 1
J 0
(-1350 3600);
DISPLAY 0.872340 (-1350 3600);
PAINT GREEN (-1350 3600);
DISPLAY INVISIBLE (-1350 3600);
FORCEADD DNS..1
(-8900 4075);
PAINT RED (-8900 4075);
FORCEPROP 2 LAST CDS_LIB mstr_misc
J 0
(-8900 4075);
DISPLAY INVISIBLE (-8900 4075);
FORCEPROP 1 LAST COMMENT_BODY TRUE
R 1
J 0
(-8825 3850);
DISPLAY 0.872340 (-8825 3850);
PAINT GREEN (-8825 3850);
DISPLAY INVISIBLE (-8825 3850);
FORCEADD DNS..1
(-6400 700);
PAINT RED (-6400 700);
FORCEPROP 2 LAST CDS_LIB mstr_misc
J 0
(-6400 700);
DISPLAY INVISIBLE (-6400 700);
FORCEPROP 1 LAST COMMENT_BODY TRUE
R 1
J 0
(-6325 475);
DISPLAY 0.872340 (-6325 475);
PAINT GREEN (-6325 475);
DISPLAY INVISIBLE (-6325 475);
FORCEADD DNS..1
(-6050 725);
PAINT RED (-6050 725);
FORCEPROP 2 LAST CDS_LIB mstr_misc
J 0
(-6050 725);
DISPLAY INVISIBLE (-6050 725);
FORCEPROP 1 LAST COMMENT_BODY TRUE
R 1
J 0
(-5975 500);
DISPLAY 0.872340 (-5975 500);
PAINT GREEN (-5975 500);
DISPLAY INVISIBLE (-5975 500);
FORCEADD DNS..1
(-8800 5950);
PAINT RED (-8800 5950);
FORCEPROP 2 LAST CDS_LIB mstr_misc
J 0
(-8800 5950);
DISPLAY INVISIBLE (-8800 5950);
FORCEPROP 1 LAST COMMENT_BODY TRUE
R 1
J 0
(-8725 5725);
DISPLAY 0.872340 (-8725 5725);
PAINT GREEN (-8725 5725);
DISPLAY INVISIBLE (-8725 5725);
FORCEADD DNS..1
(-8200 5975);
PAINT RED (-8200 5975);
FORCEPROP 2 LAST CDS_LIB mstr_misc
J 0
(-8200 5975);
DISPLAY INVISIBLE (-8200 5975);
FORCEPROP 1 LAST COMMENT_BODY TRUE
R 1
J 0
(-8125 5750);
DISPLAY 0.872340 (-8125 5750);
PAINT GREEN (-8125 5750);
DISPLAY INVISIBLE (-8125 5750);
FORCEADD DNS..1
(-7900 5950);
PAINT RED (-7900 5950);
FORCEPROP 2 LAST CDS_LIB mstr_misc
J 0
(-7900 5950);
DISPLAY INVISIBLE (-7900 5950);
FORCEPROP 1 LAST COMMENT_BODY TRUE
R 1
J 0
(-7825 5725);
DISPLAY 0.872340 (-7825 5725);
PAINT GREEN (-7825 5725);
DISPLAY INVISIBLE (-7825 5725);
FORCEADD DNS..1
(-7625 6000);
PAINT RED (-7625 6000);
FORCEPROP 2 LAST CDS_LIB mstr_misc
J 0
(-7625 6000);
DISPLAY INVISIBLE (-7625 6000);
FORCEPROP 1 LAST COMMENT_BODY TRUE
R 1
J 0
(-7550 5775);
DISPLAY 0.872340 (-7550 5775);
PAINT GREEN (-7550 5775);
DISPLAY INVISIBLE (-7550 5775);
FORCEADD DNS..1
(-7300 5950);
PAINT RED (-7300 5950);
FORCEPROP 2 LAST CDS_LIB mstr_misc
J 0
(-7300 5950);
DISPLAY INVISIBLE (-7300 5950);
FORCEPROP 1 LAST COMMENT_BODY TRUE
R 1
J 0
(-7225 5725);
DISPLAY 0.872340 (-7225 5725);
PAINT GREEN (-7225 5725);
DISPLAY INVISIBLE (-7225 5725);
FORCEADD DNS..1
(-4925 5475);
PAINT RED (-4925 5475);
FORCEPROP 2 LAST CDS_LIB mstr_misc
J 0
(-4925 5475);
DISPLAY INVISIBLE (-4925 5475);
FORCEPROP 1 LAST COMMENT_BODY TRUE
R 1
J 0
(-4850 5250);
DISPLAY 0.872340 (-4850 5250);
PAINT GREEN (-4850 5250);
DISPLAY INVISIBLE (-4850 5250);
FORCEADD DNS..1
(-3550 5275);
PAINT RED (-3550 5275);
FORCEPROP 2 LAST CDS_LIB mstr_misc
J 0
(-3550 5275);
DISPLAY INVISIBLE (-3550 5275);
FORCEPROP 1 LAST COMMENT_BODY TRUE
R 1
J 0
(-3475 5050);
DISPLAY 0.872340 (-3475 5050);
PAINT GREEN (-3475 5050);
DISPLAY INVISIBLE (-3475 5050);
FORCEADD DNS..1
(-3250 6100);
PAINT RED (-3250 6100);
FORCEPROP 2 LAST CDS_LIB mstr_misc
J 0
(-3250 6100);
DISPLAY INVISIBLE (-3250 6100);
FORCEPROP 1 LAST COMMENT_BODY TRUE
R 1
J 0
(-3175 5875);
DISPLAY 0.872340 (-3175 5875);
PAINT GREEN (-3175 5875);
DISPLAY INVISIBLE (-3175 5875);
FORCEADD DNS..1
(-2900 6075);
PAINT RED (-2900 6075);
FORCEPROP 2 LAST CDS_LIB mstr_misc
J 0
(-2900 6075);
DISPLAY INVISIBLE (-2900 6075);
FORCEPROP 1 LAST COMMENT_BODY TRUE
R 1
J 0
(-2825 5850);
DISPLAY 0.872340 (-2825 5850);
PAINT GREEN (-2825 5850);
DISPLAY INVISIBLE (-2825 5850);
FORCEADD DNS..1
(-1450 6050);
PAINT RED (-1450 6050);
FORCEPROP 2 LAST CDS_LIB mstr_misc
J 0
(-1450 6050);
DISPLAY INVISIBLE (-1450 6050);
FORCEPROP 1 LAST COMMENT_BODY TRUE
R 1
J 0
(-1375 5825);
DISPLAY 0.872340 (-1375 5825);
PAINT GREEN (-1375 5825);
DISPLAY INVISIBLE (-1375 5825);
FORCEADD QUANTA_TITLE_BLOCK_C..1
(0 0);
FORCEPROP 0 LAST CDS_CON_LAST_MODIFIED Thu Sep 14 16:13:05 2023
J 0
(-1885 15);
DISPLAY INVISIBLE (-1885 15);
FORCEPROP 1 LAST CUSTOM_TXT_CDS <CON_LAST_MODIFIED>
J 0
(-1885 15);
DISPLAY 0.978723 (-1885 15);
FORCEPROP 2 LAST CUSTOM_TXT_CDS <XR_PAGE_TITLE>
J 0
(-7890 5250);
DISPLAY 0.638298 (-7890 5250);
PAINT PINK (-7890 5250);
DISPLAY INVISIBLE (-7890 5250);
FORCEPROP 1 LAST CUSTOM_TXT_CDS <NAME_2>
J 0
(-3175 50);
FORCEPROP 1 LAST CUSTOM_TXT_CDS <NAME_1>
J 0
(-3175 175);
FORCEPROP 1 LAST CUSTOM_TXT_CDS <Q_NUMBER>
J 0
(-1403 103);
DISPLAY 1.212766 (-1403 103);
FORCEPROP 1 LAST CUSTOM_TXT_CDS <Q_PROJ>
J 0
(-2382 102);
DISPLAY 1.212766 (-2382 102);
FORCEPROP 1 LAST CUSTOM_TXT_CDS <Q_REV>
J 0
(-184 103);
DISPLAY 1.212766 (-184 103);
FORCEPROP 1 LAST CUSTOM_TXT_CDS <CON_PAGE_NUM> OF <CON_TOTAL_PAGES>
J 0
(-446 18);
DISPLAY 0.978723 (-446 18);
FORCEPROP 1 LAST Q_TITLE RETIMER_CPU1_P2(5)
J 0
(-9366 26);
DISPLAY 2.446809 (-9366 26);
PAINT GREEN (-9366 26);
FORCEPROP 2 LAST PAGE_BORDER TRUE
J 0
(-7890 5250);
DISPLAY 0.638298 (-7890 5250);
PAINT PINK (-7890 5250);
DISPLAY INVISIBLE (-7890 5250);
FORCEPROP 1 LAST CDS_LMAN_SYM_OUTLINE -9475,6775,100,-125
J 0
(0 0);
DISPLAY 0.468085 (0 0);
PAINT GREEN (0 0);
DISPLAY INVISIBLE (0 0);
FORCEPROP 2 LAST CDS_LIB pure_quanta
J 0
(0 0);
DISPLAY INVISIBLE (0 0);
FORCEPROP 2 LAST CDS_XR_PAGE_TITLE CR-343 : @T6G_MB_LIB.T6G(SCH_1):PAGE343
J 0
(-7890 5250);
DISPLAY 0.638298 (-7890 5250);
PAINT PINK (-7890 5250);
DISPLAY INVISIBLE (-7890 5250);
FORCEPROP 1 LAST Q_DEPT BU9
J 1
(-3763 49);
DISPLAY 1.957447 (-3763 49);
PAINT GREEN (-3763 49);
DISPLAY INVISIBLE (-3763 49);
FORCEPROP 1 LAST COMMENT_BODY TRUE
J 0
(12 -13);
DISPLAY 0.978723 (12 -13);
PAINT GREEN (12 -13);
DISPLAY INVISIBLE (12 -13);
FORCEADD DNS..1
(-800 1375);
PAINT RED (-800 1375);
FORCEPROP 2 LAST CDS_LIB mstr_misc
J 0
(-800 1375);
DISPLAY INVISIBLE (-800 1375);
FORCEPROP 1 LAST COMMENT_BODY TRUE
R 1
J 0
(-725 1150);
DISPLAY 0.872340 (-725 1150);
PAINT GREEN (-725 1150);
DISPLAY INVISIBLE (-725 1150);
FORCEADD DNS..1
(-525 1375);
PAINT RED (-525 1375);
FORCEPROP 2 LAST CDS_LIB mstr_misc
J 0
(-525 1375);
DISPLAY INVISIBLE (-525 1375);
FORCEPROP 1 LAST COMMENT_BODY TRUE
R 1
J 0
(-450 1150);
DISPLAY 0.872340 (-450 1150);
PAINT GREEN (-450 1150);
DISPLAY INVISIBLE (-450 1150);
FORCEADD DNS..1
(-1100 1350);
PAINT RED (-1100 1350);
FORCEPROP 2 LAST CDS_LIB mstr_misc
J 0
(-1100 1350);
DISPLAY INVISIBLE (-1100 1350);
FORCEPROP 1 LAST COMMENT_BODY TRUE
R 1
J 0
(-1025 1125);
DISPLAY 0.872340 (-1025 1125);
PAINT GREEN (-1025 1125);
DISPLAY INVISIBLE (-1025 1125);
FORCEADD DNS..1
(-1400 1400);
PAINT RED (-1400 1400);
FORCEPROP 2 LAST CDS_LIB mstr_misc
J 0
(-1400 1400);
DISPLAY INVISIBLE (-1400 1400);
FORCEPROP 1 LAST COMMENT_BODY TRUE
R 1
J 0
(-1325 1175);
DISPLAY 0.872340 (-1325 1175);
PAINT GREEN (-1325 1175);
DISPLAY INVISIBLE (-1325 1175);
WIRE 16 -1 (-2550 2275)(-1975 2275);
WIRE 16 -1 (-1500 3200)(-1500 2950);
WIRE 16 -1 (-2575 3225)(-1975 3225);
WIRE 16 -1 (-1500 3925)(-1500 4175);
WIRE 16 -1 (-600 625)(-600 475);
WIRE 16 -1 (-8950 3325)(-8950 3200);
WIRE 16 -1 (-8950 4200)(-8950 4375);
WIRE 16 -1 (-5000 5425)(-5000 5225);
WIRE 16 -1 (-5000 6150)(-5000 6325);
WIRE 16 -1 (-3750 1675)(-3375 1675);
WIRE 16 -1 (-1450 5100)(-1450 4875);
WIRE 16 -1 (-1275 5100)(-1275 4900);
WIRE 16 -1 (-1450 6225)(-1450 6125);
WIRE 16 -1 (-6125 600)(-6125 425);
WIRE 16 -1 (-6275 600)(-6275 425);
WIRE 16 -1 (-6400 1625)(-7700 1625);
FORCEPROP 2 LAST SIG_NAME SMB_RT_CPU1_P2_ROM_MUX_1D_SCL
J 0
(-7610 1635);
DISPLAY 0.680851 (-7610 1635);
WIRE 16 -1 (-5000 1625)(-6200 1625);
FORCEPROP 2 LAST SIG_NAME SMB_RT_CPU1_P2_ROM_MUX_1D_R_SCL
J 0
(-6110 1650);
DISPLAY 0.680851 (-6110 1650);
FORCEPROP 2 LASTPROP $XRERR UNIQUE?
J 0
(-6350 1650);
DISPLAY 0.638298 (-6350 1650);
PAINT MONO (-6350 1650);
DISPLAY INVISIBLE (-6350 1650);
WIRE 16 -1 (-6400 1525)(-7675 1525);
FORCEPROP 2 LAST SIG_NAME SMB_RT_CPU1_P2_ROM_MUX_1D_SDA
J 0
(-7610 1535);
DISPLAY 0.680851 (-7610 1535);
WIRE 16 -1 (-5000 1525)(-6200 1525);
FORCEPROP 2 LAST SIG_NAME SMB_RT_CPU1_P2_ROM_MUX_1D_R_SDA
J 0
(-6110 1550);
DISPLAY 0.680851 (-6110 1550);
FORCEPROP 2 LASTPROP $XRERR UNIQUE?
J 0
(-6350 1550);
DISPLAY 0.638298 (-6350 1550);
PAINT MONO (-6350 1550);
DISPLAY INVISIBLE (-6350 1550);
WIRE 16 -1 (-7825 3875)(-8950 3875);
FORCEPROP 2 LAST SIG_NAME RT_CPU1_P2_SCAN_MODE
J 0
(-8560 3885);
DISPLAY 0.680851 (-8560 3885);
WIRE 16 -1 (-8950 4000)(-8950 3875);
WIRE 16 -1 (-8950 3875)(-8950 3525);
WIRE 16 -1 (-1425 1250)(-1425 950);
WIRE 16 -1 (-2525 950)(-1425 950);
FORCEPROP 2 LAST SIG_NAME JTAG_TDI_RT_CPU1_P2
J 0
(-2360 960);
DISPLAY 0.680851 (-2360 960);
PAINT WHITE (-2360 960);
WIRE 16 -1 (-1150 1250)(-1150 1000);
WIRE 16 -1 (-2525 1000)(-1150 1000);
FORCEPROP 2 LAST SIG_NAME JTAG_TMS_RT_CPU1_P2
J 0
(-2335 1010);
DISPLAY 0.680851 (-2335 1010);
PAINT WHITE (-2335 1010);
WIRE 16 -1 (-875 1250)(-875 1050);
WIRE 16 -1 (-2525 1050)(-875 1050);
FORCEPROP 2 LAST SIG_NAME JTAG_TDO_RT_CPU1_P2
J 0
(-2335 1060);
DISPLAY 0.680851 (-2335 1060);
PAINT WHITE (-2335 1060);
WIRE 16 -1 (-600 1275)(-600 1100);
WIRE 16 -1 (-600 1100)(-600 825);
WIRE 16 -1 (-2525 1100)(-600 1100);
FORCEPROP 2 LAST SIG_NAME JTAG_TCK_RT_CPU1_P2
J 0
(-2360 1110);
DISPLAY 0.680851 (-2360 1110);
PAINT WHITE (-2360 1110);
WIRE 16 -1 (-875 1450)(-875 1600);
WIRE 16 -1 (-875 1600)(-600 1600);
WIRE 16 -1 (-1150 1600)(-875 1600);
WIRE 16 -1 (-1425 1600)(-1150 1600);
WIRE 16 -1 (-1150 1450)(-1150 1600);
WIRE 16 -1 (-600 1475)(-600 1600);
WIRE 16 -1 (-600 1600)(-600 1625);
WIRE 16 -1 (-1425 1450)(-1425 1600);
WIRE 16 -1 (-7700 4900)(-7700 4700);
WIRE 16 -1 (-7700 4700)(-7400 4700);
WIRE 16 -1 (-7700 4700)(-8000 4700);
WIRE 16 -1 (-8000 4900)(-8000 4700);
WIRE 16 -1 (-8000 4700)(-8300 4700);
WIRE 16 -1 (-7400 4875)(-7400 4700);
WIRE 16 -1 (-7400 4700)(-7400 4575);
WIRE 16 -1 (-8300 4925)(-8300 4700);
WIRE 16 -1 (-8625 4700)(-8300 4700);
WIRE 16 -1 (-8625 4925)(-8625 4700);
WIRE 16 -1 (-8925 4700)(-8625 4700);
WIRE 16 -1 (-8925 4925)(-8925 4700);
WIRE 16 -1 (-3750 3625)(-2750 3625);
FORCEPROP 2 LAST SIG_NAME JTAG_TCK_RT_CPU1_P2
J 0
(-3585 3635);
DISPLAY 0.680851 (-3585 3635);
PAINT WHITE (-3585 3635);
WIRE 16 -1 (-3750 3325)(-2775 3325);
FORCEPROP 2 LAST SIG_NAME JTAG_TDI_RT_CPU1_P2
J 0
(-3585 3335);
DISPLAY 0.680851 (-3585 3335);
PAINT WHITE (-3585 3335);
WIRE 16 -1 (-3750 3425)(-2750 3425);
FORCEPROP 2 LAST SIG_NAME JTAG_TMS_RT_CPU1_P2
J 0
(-3560 3435);
DISPLAY 0.680851 (-3560 3435);
PAINT WHITE (-3560 3435);
WIRE 16 -1 (-3750 3525)(-2750 3525);
FORCEPROP 2 LAST SIG_NAME JTAG_TDO_RT_CPU1_P2
J 0
(-3560 3535);
DISPLAY 0.680851 (-3560 3535);
PAINT WHITE (-3560 3535);
WIRE 16 -1 (-3750 3075)(-2500 3075);
FORCEPROP 2 LAST SIG_NAME JTAG_TEST_MODE_RT_CPU1_P2
J 0
(-3560 3085);
DISPLAY 0.680851 (-3560 3085);
WIRE 16 -1 (-2950 5200)(-2950 5025);
WIRE 16 -1 (-2950 5025)(-3300 5025);
WIRE 16 -1 (-3300 5200)(-3300 5025);
WIRE 16 -1 (-3300 5025)(-3600 5025);
WIRE 16 -1 (-3600 5200)(-3600 5025);
WIRE 16 -1 (-3600 5025)(-3600 4925);
WIRE 16 -1 (-3300 6400)(-2950 6400);
WIRE 16 -1 (-3300 6400)(-3300 6175);
WIRE 16 -1 (-3600 6400)(-3300 6400);
WIRE 16 -1 (-2950 6400)(-2950 6150);
WIRE 16 -1 (-3600 6175)(-3600 6400);
WIRE 16 -1 (-3600 6400)(-3600 6450);
WIRE 16 -1 (-7700 6275)(-7400 6275);
WIRE 16 -1 (-7700 6275)(-8000 6275);
WIRE 16 -1 (-7700 6275)(-7700 6050);
WIRE 16 -1 (-7400 6275)(-7400 6075);
WIRE 16 -1 (-8000 6275)(-8000 6025);
WIRE 16 -1 (-8000 6275)(-8300 6275);
WIRE 16 -1 (-8925 6275)(-8300 6275);
WIRE 16 -1 (-8300 6275)(-8300 6075);
WIRE 16 -1 (-8925 6325)(-8925 6275);
WIRE 16 -1 (-8925 6275)(-8925 6075);
WIRE 16 -1 (-3750 2075)(-2650 2075);
FORCEPROP 2 LAST SIG_NAME RST_RT_CPU1_P2_RESET_N
J 0
(-3560 2085);
DISPLAY 0.680851 (-3560 2085);
FORCEPROP 2 LASTPROP $XRERR UNIQUE?
J 0
(-3800 2085);
DISPLAY 0.638298 (-3800 2085);
PAINT MONO (-3800 2085);
DISPLAY INVISIBLE (-3800 2085);
WIRE 16 -1 (-2450 2175)(-1075 2175);
FORCEPROP 2 LAST SIG_NAME RST_RT_CPU1_P2_PERST_R_N
J 0
(-1910 2185);
DISPLAY 0.680851 (-1910 2185);
WIRE 16 -1 (-3750 2575)(-2400 2575);
FORCEPROP 2 LAST SIG_NAME RT_CPU1_P2_SCAN_MODE
J 0
(-3460 2585);
DISPLAY 0.680851 (-3460 2585);
WIRE 16 -1 (-2450 2075)(-1075 2075);
FORCEPROP 2 LAST SIG_NAME RST_RT_CPU1_P2_RESET_R_N
J 0
(-1935 2085);
DISPLAY 0.680851 (-1935 2085);
WIRE 16 -1 (-3750 2675)(-2425 2675);
FORCEPROP 2 LAST SIG_NAME RXDET_BYP_RT_CPU1_P2
J 0
(-3435 2685);
DISPLAY 0.680851 (-3435 2685);
PAINT WHITE (-3435 2685);
WIRE 16 -1 (-3750 2775)(-2425 2775);
FORCEPROP 2 LAST SIG_NAME MODE_RT_CPU1_P2
J 0
(-3435 2785);
DISPLAY 0.680851 (-3435 2785);
WIRE 16 -1 (-1500 3400)(-1500 3550);
WIRE 16 -1 (-700 3550)(-1500 3550);
FORCEPROP 2 LAST SIG_NAME RXDET_BYP_RT_CPU1_P2
J 0
(-1385 3560);
DISPLAY 0.680851 (-1385 3560);
PAINT WHITE (-1385 3560);
WIRE 16 -1 (-1500 3550)(-1500 3725);
WIRE 16 -1 (-3750 2275)(-2750 2275);
FORCEPROP 2 LAST SIG_NAME CLKREQ_RT_CPU1_P2_N
J 0
(-3485 2285);
DISPLAY 0.680851 (-3485 2285);
PAINT WHITE (-3485 2285);
FORCEPROP 2 LASTPROP $XRERR UNIQUE?
J 0
(-3725 2285);
DISPLAY 0.638298 (-3725 2285);
PAINT MONO (-3725 2285);
DISPLAY INVISIBLE (-3725 2285);
WIRE 16 -1 (-3750 2175)(-2650 2175);
FORCEPROP 2 LAST SIG_NAME RST_RT_CPU1_P2_PERST_N
J 0
(-3585 2185);
DISPLAY 0.680851 (-3585 2185);
FORCEPROP 2 LASTPROP $XRERR UNIQUE?
J 0
(-3825 2185);
DISPLAY 0.638298 (-3825 2185);
PAINT MONO (-3825 2185);
DISPLAY INVISIBLE (-3825 2185);
WIRE 16 -1 (-3750 3225)(-2775 3225);
FORCEPROP 2 LAST SIG_NAME JTAG_TRST_RT_CPU1_P2_N
J 0
(-3585 3235);
DISPLAY 0.680851 (-3585 3235);
PAINT WHITE (-3585 3235);
FORCEPROP 2 LASTPROP $XRERR UNIQUE?
J 0
(-3825 3235);
DISPLAY 0.638298 (-3825 3235);
PAINT MONO (-3825 3235);
DISPLAY INVISIBLE (-3825 3235);
WIRE 16 -1 (-6425 2875)(-7575 2875);
FORCEPROP 2 LAST SIG_NAME SMB_RT_CPU1_P2_R_SCL
J 0
(-7410 2885);
DISPLAY 0.680851 (-7410 2885);
WIRE 16 -1 (-5000 2875)(-6225 2875);
FORCEPROP 2 LAST SIG_NAME SMB_RT_CPU1_P2_R2_SCL
J 0
(-5985 2885);
DISPLAY 0.680851 (-5985 2885);
FORCEPROP 2 LASTPROP $XRERR UNIQUE?
J 0
(-6225 2885);
DISPLAY 0.638298 (-6225 2885);
PAINT MONO (-6225 2885);
DISPLAY INVISIBLE (-6225 2885);
WIRE 16 -1 (-5000 1175)(-6125 1175);
FORCEPROP 2 LAST SIG_NAME CLK_100M_RETIMER_CPU1_P2_DP
J 0
(-6035 1185);
DISPLAY 0.680851 (-6035 1185);
FORCEPROP 2 LASTPROP $XRERR UNIQUE?
J 0
(-6275 1185);
DISPLAY 0.638298 (-6275 1185);
PAINT MONO (-6275 1185);
DISPLAY INVISIBLE (-6275 1185);
WIRE 16 -1 (-6125 1175)(-6125 800);
WIRE 16 -1 (-6125 1175)(-6475 1175);
WIRE 16 -1 (-6675 1175)(-7975 1175);
FORCEPROP 2 LAST SIG_NAME CLK_100M_RETIMER_CPU1_P2_R_DP
J 0
(-7910 1185);
DISPLAY 0.680851 (-7910 1185);
WIRE 16 -1 (-5000 1025)(-6275 1025);
FORCEPROP 0 LAST SIG_NAME CLK_100M_RETIMER_CPU1_P2_DN
J 0
(-6035 1035);
DISPLAY 0.680851 (-6035 1035);
FORCEPROP 2 LASTPROP $XRERR UNIQUE?
J 0
(-6275 1035);
DISPLAY 0.638298 (-6275 1035);
PAINT MONO (-6275 1035);
DISPLAY INVISIBLE (-6275 1035);
WIRE 16 -1 (-6275 1025)(-6475 1025);
WIRE 16 -1 (-6275 1025)(-6275 800);
WIRE 16 -1 (-5000 2775)(-6225 2775);
FORCEPROP 2 LAST SIG_NAME SMB_RT_CPU1_P2_R2_SDA
J 0
(-5985 2785);
DISPLAY 0.680851 (-5985 2785);
FORCEPROP 2 LASTPROP $XRERR UNIQUE?
J 0
(-6225 2785);
DISPLAY 0.638298 (-6225 2785);
PAINT MONO (-6225 2785);
DISPLAY INVISIBLE (-6225 2785);
WIRE 16 -1 (-1275 5425)(-550 5425);
WIRE 16 -1 (-1275 5300)(-1275 5425);
FORCEPROP 2 LAST SIG_NAME RST_RT_CPU1_P2_PERST_R_N
J 0
(-1310 5460);
DISPLAY 0.680851 (-1310 5460);
WIRE 16 -1 (-1450 5300)(-1450 5575);
WIRE 16 -1 (-525 5575)(-1450 5575);
FORCEPROP 2 LAST SIG_NAME RST_RT_CPU1_P2_RESET_R_N
J 0
(-1410 5610);
DISPLAY 0.680851 (-1410 5610);
WIRE 16 -1 (-1450 5925)(-1450 5575);
WIRE 16 -1 (-5000 3225)(-5950 3225);
FORCEPROP 2 LAST SIG_NAME GPIO3_RT_CPU1_P2
J 0
(-5810 3235);
DISPLAY 0.680851 (-5810 3235);
WIRE 16 -1 (-3300 5400)(-3300 5650);
WIRE 16 -1 (-2100 5650)(-3300 5650);
FORCEPROP 2 LAST SIG_NAME RT_CPU1_P2_ADDR2
J 0
(-2885 5660);
DISPLAY 0.680851 (-2885 5660);
WIRE 16 -1 (-3300 5650)(-3300 5975);
WIRE 16 -1 (-2950 5400)(-2950 5550);
WIRE 16 -1 (-2100 5550)(-2950 5550);
FORCEPROP 2 LAST SIG_NAME RT_CPU1_P2_ADDR1
J 0
(-2885 5560);
DISPLAY 0.680851 (-2885 5560);
WIRE 16 -1 (-2950 5550)(-2950 5950);
WIRE 16 -1 (-2100 5750)(-3600 5750);
FORCEPROP 2 LAST SIG_NAME RT_CPU1_P2_ADDR3
J 0
(-2885 5785);
DISPLAY 0.680851 (-2885 5785);
WIRE 16 -1 (-3600 5975)(-3600 5750);
WIRE 16 -1 (-3600 5750)(-3600 5400);
WIRE 16 -1 (-5000 5625)(-5000 5775);
WIRE 16 -1 (-4175 5775)(-5000 5775);
FORCEPROP 2 LAST SIG_NAME MODE_RT_CPU1_P2
J 0
(-4785 5785);
DISPLAY 0.680851 (-4785 5785);
WIRE 16 -1 (-5000 5950)(-5000 5775);
WIRE 16 -1 (-8000 5100)(-8000 5500);
WIRE 16 -1 (-6400 5500)(-8000 5500);
FORCEPROP 2 LAST SIG_NAME TEST1_RT_CPU1_P2
J 0
(-6960 5510);
DISPLAY 0.680851 (-6960 5510);
WIRE 16 -1 (-8000 5825)(-8000 5500);
WIRE 16 -1 (-7700 5100)(-7700 5450);
WIRE 16 -1 (-6400 5450)(-7700 5450);
FORCEPROP 2 LAST SIG_NAME TEST2_RT_CPU1_P2
J 0
(-6960 5460);
DISPLAY 0.680851 (-6960 5460);
WIRE 16 -1 (-7700 5850)(-7700 5450);
WIRE 16 -1 (-6400 5375)(-7400 5375);
FORCEPROP 2 LAST SIG_NAME JTAG_TEST_MODE_RT_CPU1_P2
J 0
(-7210 5385);
DISPLAY 0.680851 (-7210 5385);
WIRE 16 -1 (-7400 5875)(-7400 5375);
WIRE 16 -1 (-7400 5375)(-7400 5075);
WIRE 16 -1 (-8300 5125)(-8300 5550);
WIRE 16 -1 (-6400 5550)(-8300 5550);
FORCEPROP 2 LAST SIG_NAME TEST0_RT_CPU1_P2
J 0
(-6960 5560);
DISPLAY 0.680851 (-6960 5560);
WIRE 16 -1 (-8300 5875)(-8300 5550);
WIRE 16 -1 (-5000 3325)(-5950 3325);
FORCEPROP 2 LAST SIG_NAME GPIO2_RT_CPU1_P2
J 0
(-5810 3335);
DISPLAY 0.680851 (-5810 3335);
WIRE 16 -1 (-6400 5600)(-8625 5600);
FORCEPROP 2 LAST SIG_NAME GPIO3_RT_CPU1_P2
J 0
(-6985 5610);
DISPLAY 0.680851 (-6985 5610);
WIRE 16 -1 (-8625 5600)(-8625 5125);
WIRE 16 -1 (-8925 5125)(-8925 5675);
WIRE 16 -1 (-6400 5675)(-8925 5675);
FORCEPROP 2 LAST SIG_NAME GPIO2_RT_CPU1_P2
J 0
(-6960 5685);
DISPLAY 0.680851 (-6960 5685);
WIRE 16 -1 (-8925 5875)(-8925 5675);
WIRE 16 -1 (-6425 2775)(-7575 2775);
FORCEPROP 2 LAST SIG_NAME SMB_RT_CPU1_P2_R_SDA
J 0
(-7410 2785);
DISPLAY 0.680851 (-7410 2785);
WIRE 16 -1 (-5000 2525)(-5900 2525);
FORCEPROP 2 LAST SIG_NAME RT_CPU1_P2_ADDR2
J 0
(-5760 2535);
DISPLAY 0.680851 (-5760 2535);
WIRE 16 -1 (-5000 2425)(-5900 2425);
FORCEPROP 2 LAST SIG_NAME RT_CPU1_P2_ADDR3
J 0
(-5760 2435);
DISPLAY 0.680851 (-5760 2435);
WIRE 16 -1 (-5000 2625)(-5900 2625);
FORCEPROP 2 LAST SIG_NAME RT_CPU1_P2_ADDR1
J 0
(-5760 2635);
DISPLAY 0.680851 (-5760 2635);
WIRE 16 -1 (-5000 2125)(-6075 2125);
FORCEPROP 2 LAST SIG_NAME TEST0_RT_CPU1_P2
J 0
(-5760 2135);
DISPLAY 0.680851 (-5760 2135);
WIRE 16 -1 (-5000 2025)(-6075 2025);
FORCEPROP 2 LAST SIG_NAME TEST1_RT_CPU1_P2
J 0
(-5760 2035);
DISPLAY 0.680851 (-5760 2035);
WIRE 16 -1 (-5000 1925)(-6075 1925);
FORCEPROP 2 LAST SIG_NAME TEST2_RT_CPU1_P2
J 0
(-5760 1935);
DISPLAY 0.680851 (-5760 1935);
WIRE 16 -1 (-6675 1025)(-7975 1025);
FORCEPROP 2 LAST SIG_NAME CLK_100M_RETIMER_CPU1_P2_R_DN
J 0
(-7935 1035);
DISPLAY 0.680851 (-7935 1035);
DOT 1 (-1150 1600);
DOT 1 (-600 1600);
DOT 1 (-875 1600);
DOT 1 (-600 1100);
DOT 1 (-1500 3550);
DOT 1 (-8300 4700);
DOT 1 (-8000 4700);
DOT 1 (-7400 4700);
DOT 1 (-3300 5025);
DOT 1 (-6275 1025);
DOT 1 (-8950 3875);
DOT 1 (-6125 1175);
DOT 1 (-8925 5675);
DOT 1 (-8625 4700);
DOT 1 (-8300 5550);
DOT 1 (-8000 5500);
DOT 1 (-8925 6275);
DOT 1 (-8300 6275);
DOT 1 (-8000 6275);
DOT 1 (-7700 4700);
DOT 1 (-7700 5450);
DOT 1 (-7400 5375);
DOT 1 (-7700 6275);
DOT 1 (-5000 5775);
DOT 1 (-3600 5025);
DOT 1 (-3600 5750);
DOT 1 (-3300 5650);
DOT 1 (-2950 5550);
DOT 1 (-3600 6400);
DOT 1 (-3300 6400);
DOT 1 (-1450 5575);
FORCENOTE
CPU1 P1 RT ADDR: 0X48 (8-BIT) / 0X24 (7-BIT)
(-4250 4600) 0;
DISPLAY LEFT (-4250 4600);
DISPLAY 1.595745 (-4250 4600);
QUIT
